FILE_TYPE = MACRO_DRAWING;
SET COLOR_WIRE YELLOW;
SET COLOR_PROP MONO;
SET COLOR_DOT WHITE;
SET COLOR_ARC YELLOW;
SET COLOR_BODY GREEN;
SET COLOR_NOTE MONO;
SET PROP_DISPLAY VALUE;
SET PAGE_NUMBER P92;
FORCEADD GTL2014..1
R 2
(-1825 4250);
FORCEPROP 1 LAST LOCATION U3P2
J 2
(-1425 4800);
DISPLAY 0.617021 (-1425 4800);
PAINT AQUA (-1425 4800);
FORCEPROP 1 LAST PART_NUMBER D66151-001
J 2
(-1425 3725);
DISPLAY 0.617021 (-1425 3725);
PAINT BLUE (-1425 3725);
FORCEPROP 1 LAST MATERIAL IC
J 2
(-1425 4750);
DISPLAY 0.617021 (-1425 4750);
PAINT SKYBLUE (-1425 4750);
FORCEPROP 2 LASTPIN (-1375 4500) $PN 4
J 0
(-1365 4510);
DISPLAY 0.617021 (-1365 4510);
PAINT ORANGE (-1365 4510);
FORCEPROP 2 LASTPIN (-1375 4550) $PN 14
J 0
(-1365 4560);
DISPLAY 0.617021 (-1365 4560);
PAINT ORANGE (-1365 4560);
FORCEPROP 2 LASTPIN (-2275 3950) $PN 11
J 2
(-2285 3960);
DISPLAY 0.617021 (-2285 3960);
PAINT ORANGE (-2285 3960);
FORCEPROP 2 LASTPIN (-2275 3900) $PN 8
J 2
(-2285 3910);
DISPLAY 0.617021 (-2285 3910);
PAINT ORANGE (-2285 3910);
FORCEPROP 2 LASTPIN (-2275 3850) $PN 7
J 2
(-2285 3860);
DISPLAY 0.617021 (-2285 3860);
PAINT ORANGE (-2285 3860);
FORCEPROP 2 LASTPIN (-1375 4400) $PN 1
J 0
(-1365 4410);
DISPLAY 0.617021 (-1365 4410);
PAINT ORANGE (-1365 4410);
FORCEPROP 2 LASTPIN (-2275 4250) $PN 6
J 2
(-2285 4260);
DISPLAY 0.617021 (-2285 4260);
PAINT ORANGE (-2285 4260);
FORCEPROP 2 LASTPIN (-2275 4200) $PN 5
J 2
(-2285 4210);
DISPLAY 0.617021 (-2285 4210);
PAINT ORANGE (-2285 4210);
FORCEPROP 2 LASTPIN (-2275 4150) $PN 3
J 2
(-2285 4160);
DISPLAY 0.617021 (-2285 4160);
PAINT ORANGE (-2285 4160);
FORCEPROP 2 LASTPIN (-2275 4100) $PN 2
J 2
(-2285 4110);
DISPLAY 0.617021 (-2285 4110);
PAINT ORANGE (-2285 4110);
FORCEPROP 2 LASTPIN (-1375 4250) $PN 9
J 0
(-1365 4260);
DISPLAY 0.617021 (-1365 4260);
PAINT ORANGE (-1365 4260);
FORCEPROP 2 LASTPIN (-1375 4200) $PN 10
J 0
(-1365 4210);
DISPLAY 0.617021 (-1365 4210);
PAINT ORANGE (-1365 4210);
FORCEPROP 2 LASTPIN (-1375 4150) $PN 12
J 0
(-1365 4160);
DISPLAY 0.617021 (-1365 4160);
PAINT ORANGE (-1365 4160);
FORCEPROP 2 LASTPIN (-1375 4100) $PN 13
J 0
(-1365 4110);
DISPLAY 0.617021 (-1365 4110);
PAINT ORANGE (-1365 4110);
FORCEPROP 1 LAST PACK_TYPE SM
J 2
(-1425 4850);
PAINT SKYBLUE (-1425 4850);
DISPLAY INVISIBLE (-1425 4850);
FORCEPROP 2 LAST SEC_TYPE SM
J 0
(-1425 4850);
DISPLAY 1.021277 (-1425 4850);
PAINT ORANGE (-1425 4850);
DISPLAY INVISIBLE (-1425 4850);
FORCEPROP 2 LAST BOM_COST PROC_SIDEBAND
J 2
(-1825 4250);
PAINT MONO (-1825 4250);
DISPLAY INVISIBLE (-1825 4250);
FORCEPROP 2 LAST CDS_LIB mstr_digital
J 0
(-1825 4250);
PAINT ORANGE (-1825 4250);
DISPLAY INVISIBLE (-1825 4250);
FORCEPROP 2 LAST SEC 1
J 0
(-1425 4850);
DISPLAY 0.680851 (-1425 4850);
PAINT MONO (-1425 4850);
DISPLAY INVISIBLE (-1425 4850);
FORCEPROP 2 LAST CDS_LOCATION U3P2
J 2
(-1425 4800);
DISPLAY 0.617021 (-1425 4800);
PAINT AQUA (-1425 4800);
DISPLAY INVISIBLE (-1425 4800);
FORCEPROP 1 LAST PATH I1
J 2
(-1825 4750);
PAINT GREEN (-1825 4750);
DISPLAY INVISIBLE (-1825 4750);
FORCEPROP 2 LAST ROOM PROC_SIDEBAND
J 2
(-1425 4900);
PAINT MONO (-1425 4900);
DISPLAY INVISIBLE (-1425 4900);
FORCEADD PVCCIO_CPU1..1
(-2900 4750);
FORCEPROP 3 LASTPIN (-2900 4700) SIG_NAME PVCCIO_CPU1\g
J 0
(-2890 4710);
DISPLAY 0.659574 (-2890 4710);
PAINT MONO (-2890 4710);
DISPLAY INVISIBLE (-2890 4710);
FORCEPROP 1 LAST VOLTAGE 1.1V
J 0
(-2945 4707);
DISPLAY 0.340426 (-2945 4707);
PAINT SKYBLUE (-2945 4707);
DISPLAY INVISIBLE (-2945 4707);
FORCEPROP 2 LAST CDS_LIB mstr_symbols
J 0
(-2900 4750);
PAINT ORANGE (-2900 4750);
DISPLAY INVISIBLE (-2900 4750);
FORCEPROP 1 LAST BODY_TYPE PLUMBING
J 0
(-2945 4707);
DISPLAY 0.340426 (-2945 4707);
PAINT GREEN (-2945 4707);
DISPLAY INVISIBLE (-2945 4707);
FORCEPROP 1 LAST PATH I10
J 0
(-2850 4775);
DISPLAY 0.872340 (-2850 4775);
PAINT AQUA (-2850 4775);
DISPLAY INVISIBLE (-2850 4775);
FORCEPROP 1 LAST HDL_POWER PVCCIO_CPU1
J 1
(-2900 4800);
DISPLAY 0.872340 (-2900 4800);
PAINT GREEN (-2900 4800);
DISPLAY INVISIBLE (-2900 4800);
FORCEADD RES..2
(-4350 4600);
FORCEPROP 1 LAST LOCATION R7P18
J 0
(-4305 4725);
DISPLAY 0.617021 (-4305 4725);
PAINT AQUA (-4305 4725);
FORCEPROP 1 LAST PART_NUMBER G21796-009
J 0
(-4310 4475);
DISPLAY 0.617021 (-4310 4475);
PAINT BLUE (-4310 4475);
FORCEPROP 1 LAST VALUE 150.0
J 0
(-4305 4675);
DISPLAY 0.617021 (-4305 4675);
PAINT SKYBLUE (-4305 4675);
FORCEPROP 1 LAST TOLERANCE 1%
J 0
(-4305 4625);
DISPLAY 0.617021 (-4305 4625);
PAINT SKYBLUE (-4305 4625);
FORCEPROP 1 LAST PACK_TYPE 0402
J 0
(-4310 4425);
DISPLAY 0.617021 (-4310 4425);
PAINT SKYBLUE (-4310 4425);
FORCEPROP 1 LAST MATERIAL CHIP
J 0
(-4310 4525);
DISPLAY 0.617021 (-4310 4525);
PAINT SKYBLUE (-4310 4525);
FORCEPROP 1 LAST WATTAGE 1/16W
J 0
(-4310 4575);
DISPLAY 0.617021 (-4310 4575);
PAINT SKYBLUE (-4310 4575);
FORCEPROP 1 LASTPIN (-4350 4500) $PN 2
J 0
(-4345 4510);
DISPLAY 0.617021 (-4345 4510);
PAINT MONO (-4345 4510);
FORCEPROP 1 LASTPIN (-4350 4700) $PN 1
J 0
(-4345 4662);
DISPLAY 0.617021 (-4345 4662);
PAINT MONO (-4345 4662);
FORCEPROP 2 LAST CDS_LIB mstr_discrete
J 2
(-4350 4600);
PAINT ORANGE (-4350 4600);
DISPLAY INVISIBLE (-4350 4600);
FORCEPROP 2 LAST BOM_COST PROC
J 0
(-4350 4600);
PAINT MONO (-4350 4600);
DISPLAY INVISIBLE (-4350 4600);
FORCEPROP 2 LAST SEC_TYPE 0402
J 0
(-4300 4825);
DISPLAY 1.021277 (-4300 4825);
PAINT ORANGE (-4300 4825);
DISPLAY INVISIBLE (-4300 4825);
FORCEPROP 2 LAST SEC 1
J 2
(-4300 4825);
DISPLAY 0.936170 (-4300 4825);
PAINT MONO (-4300 4825);
DISPLAY INVISIBLE (-4300 4825);
FORCEPROP 2 LAST CDS_LOCATION R7P18
J 0
(-4305 4725);
DISPLAY 0.617021 (-4305 4725);
PAINT AQUA (-4305 4725);
DISPLAY INVISIBLE (-4305 4725);
FORCEPROP 1 LAST PATH I100
J 0
(-4300 4775);
DISPLAY 0.978723 (-4300 4775);
PAINT WHITE (-4300 4775);
DISPLAY INVISIBLE (-4300 4775);
FORCEPROP 2 LAST ROOM PROC_SIDEBAND
J 0
(-4325 4375);
PAINT ORANGE (-4325 4375);
DISPLAY INVISIBLE (-4325 4375);
FORCEADD RES..2
R 2
(-4450 4600);
FORCEPROP 1 LAST LOCATION R4R2
J 2
(-4495 4725);
DISPLAY 0.617021 (-4495 4725);
PAINT AQUA (-4495 4725);
FORCEPROP 1 LAST PART_NUMBER G21796-009
J 2
(-4490 4475);
DISPLAY 0.617021 (-4490 4475);
PAINT BLUE (-4490 4475);
FORCEPROP 1 LAST VALUE 150.0
J 2
(-4495 4675);
DISPLAY 0.617021 (-4495 4675);
PAINT SKYBLUE (-4495 4675);
FORCEPROP 1 LAST TOLERANCE 1%
J 2
(-4495 4625);
DISPLAY 0.617021 (-4495 4625);
PAINT SKYBLUE (-4495 4625);
FORCEPROP 1 LAST PACK_TYPE 0402
J 2
(-4490 4425);
DISPLAY 0.617021 (-4490 4425);
PAINT SKYBLUE (-4490 4425);
FORCEPROP 1 LAST MATERIAL CHIP
J 2
(-4490 4525);
DISPLAY 0.617021 (-4490 4525);
PAINT SKYBLUE (-4490 4525);
FORCEPROP 1 LAST WATTAGE 1/16W
J 2
(-4490 4575);
DISPLAY 0.617021 (-4490 4575);
PAINT SKYBLUE (-4490 4575);
FORCEPROP 1 LASTPIN (-4450 4500) $PN 2
J 2
(-4455 4510);
DISPLAY 0.617021 (-4455 4510);
PAINT MONO (-4455 4510);
FORCEPROP 1 LASTPIN (-4450 4700) $PN 1
J 2
(-4455 4662);
DISPLAY 0.617021 (-4455 4662);
PAINT MONO (-4455 4662);
FORCEPROP 2 LAST SEC_TYPE 0402
J 0
(-4500 4825);
DISPLAY 1.021277 (-4500 4825);
PAINT ORANGE (-4500 4825);
DISPLAY INVISIBLE (-4500 4825);
FORCEPROP 2 LAST CDS_LIB mstr_discrete
J 0
(-4450 4600);
PAINT ORANGE (-4450 4600);
DISPLAY INVISIBLE (-4450 4600);
FORCEPROP 2 LAST BOM_COST PROC
J 2
(-4450 4600);
PAINT MONO (-4450 4600);
DISPLAY INVISIBLE (-4450 4600);
FORCEPROP 2 LAST SEC 1
J 0
(-4500 4825);
DISPLAY 0.936170 (-4500 4825);
PAINT MONO (-4500 4825);
DISPLAY INVISIBLE (-4500 4825);
FORCEPROP 2 LAST CDS_LOCATION R4R2
J 2
(-4495 4725);
DISPLAY 0.617021 (-4495 4725);
PAINT AQUA (-4495 4725);
DISPLAY INVISIBLE (-4495 4725);
FORCEPROP 1 LAST PATH I101
J 2
(-4500 4775);
DISPLAY 0.978723 (-4500 4775);
PAINT WHITE (-4500 4775);
DISPLAY INVISIBLE (-4500 4775);
FORCEPROP 2 LAST ROOM PROC_SIDEBAND
J 2
(-4475 4375);
PAINT ORANGE (-4475 4375);
DISPLAY INVISIBLE (-4475 4375);
FORCEADD OFFPAGE..1
(-5150 4100);
FORCEPROP 2 LAST $XR0 55 
J 0
(-5371 4100);
DISPLAY 0.638298 (-5371 4100);
PAINT MONO (-5371 4100);
FORCEPROP 2 LAST CDS_LIB mstr_standard
J 0
(-5150 4100);
PAINT ORANGE (-5150 4100);
DISPLAY INVISIBLE (-5150 4100);
FORCEPROP 1 LAST OFFPAGE TRUE
J 0
(-4825 3975);
PAINT GREEN (-4825 3975);
DISPLAY INVISIBLE (-4825 3975);
FORCEPROP 1 LAST COMMENT_BODY TRUE
J 0
(-5025 4000);
DISPLAY 1.170213 (-5025 4000);
PAINT GREEN (-5025 4000);
DISPLAY INVISIBLE (-5025 4000);
FORCEPROP 2 LAST PATH I102
J 0
(-5350 4150);
DISPLAY 1.021277 (-5350 4150);
PAINT ORANGE (-5350 4150);
DISPLAY INVISIBLE (-5350 4150);
FORCEADD OFFPAGE..1
(-5150 4350);
FORCEPROP 2 LAST $XR0 21 
J 0
(-5371 4350);
DISPLAY 0.638298 (-5371 4350);
PAINT MONO (-5371 4350);
FORCEPROP 2 LAST CDS_LIB mstr_standard
J 0
(-5150 4350);
PAINT ORANGE (-5150 4350);
DISPLAY INVISIBLE (-5150 4350);
FORCEPROP 1 LAST OFFPAGE TRUE
J 0
(-4825 4225);
PAINT GREEN (-4825 4225);
DISPLAY INVISIBLE (-4825 4225);
FORCEPROP 1 LAST COMMENT_BODY TRUE
J 0
(-5025 4250);
DISPLAY 1.170213 (-5025 4250);
PAINT GREEN (-5025 4250);
DISPLAY INVISIBLE (-5025 4250);
FORCEPROP 2 LAST PATH I103
J 0
(-5350 4400);
DISPLAY 1.021277 (-5350 4400);
PAINT ORANGE (-5350 4400);
DISPLAY INVISIBLE (-5350 4400);
FORCEADD PVCCIO_CPU0..1
(125 5425);
FORCEPROP 3 LASTPIN (125 5375) SIG_NAME PVCCIO_CPU0\g
J 0
(135 5385);
DISPLAY 0.659574 (135 5385);
PAINT MONO (135 5385);
DISPLAY INVISIBLE (135 5385);
FORCEPROP 1 LAST VOLTAGE 1.1V
J 0
(80 5382);
DISPLAY 0.340426 (80 5382);
PAINT SKYBLUE (80 5382);
DISPLAY INVISIBLE (80 5382);
FORCEPROP 2 LAST CDS_LIB mstr_symbols
J 0
(125 5425);
PAINT ORANGE (125 5425);
DISPLAY INVISIBLE (125 5425);
FORCEPROP 1 LAST BODY_TYPE PLUMBING
J 0
(80 5382);
DISPLAY 0.340426 (80 5382);
PAINT GREEN (80 5382);
DISPLAY INVISIBLE (80 5382);
FORCEPROP 1 LAST PATH I104
J 0
(175 5450);
DISPLAY 0.872340 (175 5450);
PAINT AQUA (175 5450);
DISPLAY INVISIBLE (175 5450);
FORCEPROP 1 LAST HDL_POWER PVCCIO_CPU0
J 1
(125 5475);
DISPLAY 0.872340 (125 5475);
PAINT GREEN (125 5475);
DISPLAY INVISIBLE (125 5475);
FORCEADD RES..1
(-125 3750);
FORCEPROP 1 LAST LOCATION R3P46
J 0
(-175 3800);
DISPLAY 0.617021 (-175 3800);
PAINT AQUA (-175 3800);
FORCEPROP 1 LAST PART_NUMBER G21796-074
J 0
(175 3850);
DISPLAY 0.617021 (175 3850);
PAINT BLUE (175 3850);
FORCEPROP 1 LAST VALUE 33.2
J 2
(-150 3650);
DISPLAY 0.617021 (-150 3650);
PAINT SKYBLUE (-150 3650);
FORCEPROP 1 LAST TOLERANCE 1%
J 0
(-125 3650);
DISPLAY 0.617021 (-125 3650);
PAINT SKYBLUE (-125 3650);
FORCEPROP 1 LAST PACK_TYPE 0402
J 0
(150 3650);
DISPLAY 0.617021 (150 3650);
PAINT SKYBLUE (150 3650);
FORCEPROP 1 LAST MATERIAL CHIP
J 0
(-25 3650);
DISPLAY 0.617021 (-25 3650);
PAINT SKYBLUE (-25 3650);
FORCEPROP 1 LAST WATTAGE 1/16W
J 2
(-275 3650);
DISPLAY 0.617021 (-275 3650);
PAINT SKYBLUE (-275 3650);
FORCEPROP 1 LASTPIN (-25 3750) $PN 2
J 0
(-63 3762);
DISPLAY 0.617021 (-63 3762);
PAINT ORANGE (-63 3762);
FORCEPROP 1 LASTPIN (-225 3750) $PN 1
J 0
(-213 3762);
DISPLAY 0.617021 (-213 3762);
PAINT ORANGE (-213 3762);
FORCEPROP 2 LAST SEC_TYPE 0402
J 0
(-175 3950);
DISPLAY 1.021277 (-175 3950);
PAINT ORANGE (-175 3950);
DISPLAY INVISIBLE (-175 3950);
FORCEPROP 2 LAST BOM_COST PROC_SIDEBAND
J 2
(-125 3750);
PAINT MONO (-125 3750);
DISPLAY INVISIBLE (-125 3750);
FORCEPROP 2 LAST CDS_LIB mstr_discrete
J 0
(-125 3750);
PAINT ORANGE (-125 3750);
DISPLAY INVISIBLE (-125 3750);
FORCEPROP 2 LAST SEC 1
J 0
(-175 3950);
DISPLAY 0.680851 (-175 3950);
PAINT MONO (-175 3950);
DISPLAY INVISIBLE (-175 3950);
FORCEPROP 2 LAST CDS_LOCATION R3P46
J 0
(-175 3800);
DISPLAY 0.617021 (-175 3800);
PAINT AQUA (-175 3800);
DISPLAY INVISIBLE (-175 3800);
FORCEPROP 1 LAST PATH I12
J 0
(-175 3900);
DISPLAY 0.978723 (-175 3900);
PAINT WHITE (-175 3900);
DISPLAY INVISIBLE (-175 3900);
FORCEPROP 2 LAST ROOM PROC_SIDEBAND
J 0
(-200 3675);
DISPLAY 0.617021 (-200 3675);
PAINT ORANGE (-200 3675);
DISPLAY INVISIBLE (-200 3675);
FORCEADD RES..1
(-125 4000);
FORCEPROP 1 LAST PART_NUMBER G21796-074
J 0
(150 4100);
DISPLAY 0.617021 (150 4100);
PAINT BLUE (150 4100);
FORCEPROP 1 LAST VALUE 33.2
J 2
(-150 3900);
DISPLAY 0.617021 (-150 3900);
PAINT SKYBLUE (-150 3900);
FORCEPROP 1 LAST TOLERANCE 1%
J 0
(-125 3900);
DISPLAY 0.617021 (-125 3900);
PAINT SKYBLUE (-125 3900);
FORCEPROP 1 LAST PACK_TYPE 0402
J 0
(0 3850);
DISPLAY 0.617021 (0 3850);
PAINT SKYBLUE (0 3850);
FORCEPROP 1 LAST MATERIAL CHIP
J 0
(-125 3850);
DISPLAY 0.617021 (-125 3850);
PAINT SKYBLUE (-125 3850);
FORCEPROP 1 LAST WATTAGE 1/16W
J 2
(-150 3850);
DISPLAY 0.617021 (-150 3850);
PAINT SKYBLUE (-150 3850);
FORCEPROP 1 LASTPIN (-25 4000) $PN 2
J 0
(-63 4012);
DISPLAY 0.617021 (-63 4012);
PAINT ORANGE (-63 4012);
FORCEPROP 1 LASTPIN (-225 4000) $PN 1
J 0
(-213 4012);
DISPLAY 0.617021 (-213 4012);
PAINT ORANGE (-213 4012);
FORCEPROP 1 LAST LOCATION R3P43
J 0
(-175 4050);
DISPLAY 0.617021 (-175 4050);
PAINT AQUA (-175 4050);
FORCEPROP 2 LAST SEC_TYPE 0402
J 0
(-175 4200);
DISPLAY 1.021277 (-175 4200);
PAINT ORANGE (-175 4200);
DISPLAY INVISIBLE (-175 4200);
FORCEPROP 2 LAST BOM_COST PROC_SIDEBAND
J 2
(-125 4000);
PAINT MONO (-125 4000);
DISPLAY INVISIBLE (-125 4000);
FORCEPROP 2 LAST CDS_LIB mstr_discrete
J 0
(-125 4000);
PAINT ORANGE (-125 4000);
DISPLAY INVISIBLE (-125 4000);
FORCEPROP 2 LAST SEC 1
J 0
(-175 4200);
DISPLAY 0.680851 (-175 4200);
PAINT MONO (-175 4200);
DISPLAY INVISIBLE (-175 4200);
FORCEPROP 2 LAST CDS_LOCATION R3P43
J 0
(-175 4050);
DISPLAY 0.617021 (-175 4050);
PAINT AQUA (-175 4050);
DISPLAY INVISIBLE (-175 4050);
FORCEPROP 1 LAST PATH I13
J 0
(-175 4150);
DISPLAY 0.978723 (-175 4150);
PAINT WHITE (-175 4150);
DISPLAY INVISIBLE (-175 4150);
FORCEPROP 2 LAST ROOM PROC_SIDEBAND
J 0
(-200 3925);
DISPLAY 0.617021 (-200 3925);
PAINT ORANGE (-200 3925);
DISPLAY INVISIBLE (-200 3925);
FORCEADD RES..1
(-125 4250);
FORCEPROP 1 LAST LOCATION R3P42
J 0
(-175 4300);
DISPLAY 0.617021 (-175 4300);
PAINT AQUA (-175 4300);
FORCEPROP 1 LAST PART_NUMBER G21796-074
J 0
(-175 4350);
DISPLAY 0.617021 (-175 4350);
PAINT BLUE (-175 4350);
FORCEPROP 1 LAST VALUE 33.2
J 2
(-150 4150);
DISPLAY 0.617021 (-150 4150);
PAINT SKYBLUE (-150 4150);
FORCEPROP 1 LAST TOLERANCE 1%
J 0
(-125 4150);
DISPLAY 0.617021 (-125 4150);
PAINT SKYBLUE (-125 4150);
FORCEPROP 1 LAST PACK_TYPE 0402
J 0
(0 4100);
DISPLAY 0.617021 (0 4100);
PAINT SKYBLUE (0 4100);
FORCEPROP 1 LAST MATERIAL CHIP
J 0
(-125 4100);
DISPLAY 0.617021 (-125 4100);
PAINT SKYBLUE (-125 4100);
FORCEPROP 1 LASTPIN (-25 4250) $PN 2
J 0
(-63 4262);
DISPLAY 0.617021 (-63 4262);
PAINT ORANGE (-63 4262);
FORCEPROP 1 LASTPIN (-225 4250) $PN 1
J 0
(-213 4262);
DISPLAY 0.617021 (-213 4262);
PAINT ORANGE (-213 4262);
FORCEPROP 1 LAST WATTAGE 1/16W
J 2
(-150 4100);
DISPLAY 0.617021 (-150 4100);
PAINT SKYBLUE (-150 4100);
FORCEPROP 2 LAST SEC_TYPE 0402
J 0
(-175 4450);
DISPLAY 1.021277 (-175 4450);
PAINT ORANGE (-175 4450);
DISPLAY INVISIBLE (-175 4450);
FORCEPROP 2 LAST BOM_COST PROC_SIDEBAND
J 2
(-125 4250);
PAINT MONO (-125 4250);
DISPLAY INVISIBLE (-125 4250);
FORCEPROP 2 LAST CDS_LIB mstr_discrete
J 0
(-125 4250);
PAINT ORANGE (-125 4250);
DISPLAY INVISIBLE (-125 4250);
FORCEPROP 2 LAST SEC 1
J 0
(-175 4450);
DISPLAY 0.680851 (-175 4450);
PAINT MONO (-175 4450);
DISPLAY INVISIBLE (-175 4450);
FORCEPROP 2 LAST CDS_LOCATION R3P42
J 0
(-175 4300);
DISPLAY 0.617021 (-175 4300);
PAINT AQUA (-175 4300);
DISPLAY INVISIBLE (-175 4300);
FORCEPROP 1 LAST PATH I14
J 0
(-175 4400);
DISPLAY 0.978723 (-175 4400);
PAINT WHITE (-175 4400);
DISPLAY INVISIBLE (-175 4400);
FORCEPROP 2 LAST ROOM PROC_SIDEBAND
J 0
(-200 4175);
DISPLAY 0.617021 (-200 4175);
PAINT ORANGE (-200 4175);
DISPLAY INVISIBLE (-200 4175);
FORCEADD OFFPAGE..5
R 2
(1050 3750);
FORCEPROP 2 LAST $XR0 191 
J 0
(1239 3750);
DISPLAY 0.638298 (1239 3750);
PAINT MONO (1239 3750);
FORCEPROP 2 LAST CDS_LIB mstr_standard
J 0
(1050 3750);
PAINT ORANGE (1050 3750);
DISPLAY INVISIBLE (1050 3750);
FORCEPROP 1 LAST OFFPAGE TRUE
J 2
(725 3625);
PAINT GREEN (725 3625);
DISPLAY INVISIBLE (725 3625);
FORCEPROP 1 LAST COMMENT_BODY TRUE
J 2
(950 3675);
DISPLAY 1.170213 (950 3675);
PAINT GREEN (950 3675);
DISPLAY INVISIBLE (950 3675);
FORCEPROP 2 LAST PATH I16
J 0
(1250 3800);
DISPLAY 1.021277 (1250 3800);
PAINT ORANGE (1250 3800);
DISPLAY INVISIBLE (1250 3800);
FORCEADD OFFPAGE..2
(1050 4250);
FORCEPROP 2 LAST $XR0 191 
J 0
(1239 4250);
DISPLAY 0.638298 (1239 4250);
PAINT MONO (1239 4250);
FORCEPROP 2 LAST CDS_LIB mstr_standard
J 0
(1050 4250);
PAINT MONO (1050 4250);
DISPLAY INVISIBLE (1050 4250);
FORCEPROP 1 LAST OFFPAGE TRUE
J 0
(1375 4125);
PAINT GREEN (1375 4125);
DISPLAY INVISIBLE (1375 4125);
FORCEPROP 1 LAST COMMENT_BODY TRUE
J 0
(1005 4155);
DISPLAY 1.085106 (1005 4155);
PAINT GREEN (1005 4155);
DISPLAY INVISIBLE (1005 4155);
FORCEPROP 2 LAST PATH I18
J 0
(1250 4300);
DISPLAY 1.021277 (1250 4300);
PAINT ORANGE (1250 4300);
DISPLAY INVISIBLE (1250 4300);
FORCEADD RES..2
(-2850 2325);
FORCEPROP 1 LAST LOCATION R7E2
J 0
(-2805 2450);
DISPLAY 0.617021 (-2805 2450);
PAINT AQUA (-2805 2450);
FORCEPROP 1 LAST PART_NUMBER G21796-267
J 0
(-2810 2200);
DISPLAY 0.617021 (-2810 2200);
PAINT BLUE (-2810 2200);
FORCEPROP 1 LAST VALUE 75
J 0
(-2805 2400);
DISPLAY 0.617021 (-2805 2400);
PAINT SKYBLUE (-2805 2400);
FORCEPROP 1 LAST TOLERANCE 1.0%
J 0
(-2805 2350);
DISPLAY 0.617021 (-2805 2350);
PAINT SKYBLUE (-2805 2350);
FORCEPROP 1 LAST PACK_TYPE 0402
J 0
(-2810 2150);
DISPLAY 0.617021 (-2810 2150);
PAINT SKYBLUE (-2810 2150);
FORCEPROP 1 LAST MATERIAL CHIP
J 0
(-2810 2250);
DISPLAY 0.617021 (-2810 2250);
PAINT SKYBLUE (-2810 2250);
FORCEPROP 1 LAST WATTAGE 1/16W
J 0
(-2810 2300);
DISPLAY 0.617021 (-2810 2300);
PAINT SKYBLUE (-2810 2300);
FORCEPROP 1 LASTPIN (-2850 2225) $PN 2
J 0
(-2845 2235);
DISPLAY 0.617021 (-2845 2235);
PAINT ORANGE (-2845 2235);
FORCEPROP 1 LASTPIN (-2850 2425) $PN 1
J 0
(-2845 2387);
DISPLAY 0.617021 (-2845 2387);
PAINT ORANGE (-2845 2387);
FORCEPROP 2 LAST SEC_TYPE 0402
J 0
(-2800 2550);
DISPLAY 1.021277 (-2800 2550);
PAINT ORANGE (-2800 2550);
DISPLAY INVISIBLE (-2800 2550);
FORCEPROP 2 LAST CDS_LIB mstr_discrete
J 0
(-2850 2325);
PAINT ORANGE (-2850 2325);
DISPLAY INVISIBLE (-2850 2325);
FORCEPROP 2 LAST BOM_COST PROC_SIDEBAND
J 0
(-2850 2325);
PAINT MONO (-2850 2325);
DISPLAY INVISIBLE (-2850 2325);
FORCEPROP 2 LAST SEC 1
J 0
(-2800 2550);
DISPLAY 0.680851 (-2800 2550);
PAINT MONO (-2800 2550);
DISPLAY INVISIBLE (-2800 2550);
FORCEPROP 2 LAST CDS_LOCATION R7E2
J 0
(-2805 2450);
DISPLAY 0.617021 (-2805 2450);
PAINT AQUA (-2805 2450);
DISPLAY INVISIBLE (-2805 2450);
FORCEPROP 1 LAST PATH I19
J 0
(-2800 2500);
DISPLAY 0.978723 (-2800 2500);
PAINT WHITE (-2800 2500);
DISPLAY INVISIBLE (-2800 2500);
FORCEPROP 2 LAST ROOM PROC_SIDEBAND
J 0
(-2825 2100);
PAINT ORANGE (-2825 2100);
DISPLAY INVISIBLE (-2825 2100);
FORCEADD GND..1
(-2550 3725);
FORCEPROP 3 LASTPIN (-2550 3775) SIG_NAME GND\g
J 0
(-2540 3785);
DISPLAY 0.659574 (-2540 3785);
PAINT MONO (-2540 3785);
DISPLAY INVISIBLE (-2540 3785);
FORCEPROP 1 LAST VOLTAGE 0
J 0
(-2550 3725);
PAINT SKYBLUE (-2550 3725);
DISPLAY INVISIBLE (-2550 3725);
FORCEPROP 1 LAST SIZE 1B
J 0
(-2475 3675);
DISPLAY 1.212766 (-2475 3675);
PAINT GREEN (-2475 3675);
DISPLAY INVISIBLE (-2475 3675);
FORCEPROP 2 LAST CDS_LIB mstr_symbols
J 0
(-2550 3725);
PAINT ORANGE (-2550 3725);
DISPLAY INVISIBLE (-2550 3725);
FORCEPROP 1 LAST BODY_TYPE PLUMBING
J 0
(-2595 3682);
DISPLAY 0.340426 (-2595 3682);
PAINT GREEN (-2595 3682);
DISPLAY INVISIBLE (-2595 3682);
FORCEPROP 1 LAST PATH I2
J 0
(-2475 3725);
DISPLAY 0.872340 (-2475 3725);
PAINT AQUA (-2475 3725);
DISPLAY INVISIBLE (-2475 3725);
FORCEPROP 1 LAST HDL_POWER GND
J 0
(-2550 3875);
DISPLAY 1.212766 (-2550 3875);
PAINT GREEN (-2550 3875);
DISPLAY INVISIBLE (-2550 3875);
FORCEADD OFFPAGE..2
(1075 2050);
FORCEPROP 2 LAST $XR0 191 
J 0
(1264 2050);
DISPLAY 0.638298 (1264 2050);
PAINT MONO (1264 2050);
FORCEPROP 2 LAST CDS_LIB mstr_standard
J 0
(1075 2050);
PAINT MONO (1075 2050);
DISPLAY INVISIBLE (1075 2050);
FORCEPROP 1 LAST OFFPAGE TRUE
J 0
(1400 1925);
PAINT GREEN (1400 1925);
DISPLAY INVISIBLE (1400 1925);
FORCEPROP 1 LAST COMMENT_BODY TRUE
J 0
(1030 1955);
DISPLAY 1.085106 (1030 1955);
PAINT GREEN (1030 1955);
DISPLAY INVISIBLE (1030 1955);
FORCEPROP 2 LAST PATH I20
J 0
(1250 2125);
DISPLAY 1.021277 (1250 2125);
PAINT ORANGE (1250 2125);
DISPLAY INVISIBLE (1250 2125);
FORCEADD OFFPAGE..5
R 2
(1075 1550);
FORCEPROP 2 LAST $XR0 191 
J 0
(1264 1550);
DISPLAY 0.638298 (1264 1550);
PAINT MONO (1264 1550);
FORCEPROP 2 LAST CDS_LIB mstr_standard
J 0
(1075 1550);
PAINT ORANGE (1075 1550);
DISPLAY INVISIBLE (1075 1550);
FORCEPROP 1 LAST OFFPAGE TRUE
J 2
(750 1425);
PAINT GREEN (750 1425);
DISPLAY INVISIBLE (750 1425);
FORCEPROP 1 LAST COMMENT_BODY TRUE
J 2
(975 1475);
DISPLAY 1.170213 (975 1475);
PAINT GREEN (975 1475);
DISPLAY INVISIBLE (975 1475);
FORCEPROP 2 LAST PATH I22
J 0
(1250 1625);
DISPLAY 1.021277 (1250 1625);
PAINT ORANGE (1250 1625);
DISPLAY INVISIBLE (1250 1625);
FORCEADD RES..1
(-125 2050);
FORCEPROP 1 LAST LOCATION R7D34
J 0
(-175 2100);
DISPLAY 0.617021 (-175 2100);
PAINT AQUA (-175 2100);
FORCEPROP 1 LAST PART_NUMBER G21796-074
J 0
(-50 1950);
DISPLAY 0.617021 (-50 1950);
PAINT BLUE (-50 1950);
FORCEPROP 1 LAST VALUE 33.2
J 2
(-150 2000);
DISPLAY 0.617021 (-150 2000);
PAINT SKYBLUE (-150 2000);
FORCEPROP 1 LAST TOLERANCE 1%
J 0
(-125 2000);
DISPLAY 0.617021 (-125 2000);
PAINT SKYBLUE (-125 2000);
FORCEPROP 1 LAST PACK_TYPE 0402
J 0
(-25 2000);
DISPLAY 0.617021 (-25 2000);
PAINT SKYBLUE (-25 2000);
FORCEPROP 1 LAST MATERIAL CHIP
J 0
(-175 1950);
DISPLAY 0.617021 (-175 1950);
PAINT SKYBLUE (-175 1950);
FORCEPROP 1 LAST WATTAGE 1/16W
J 2
(-200 1950);
DISPLAY 0.617021 (-200 1950);
PAINT SKYBLUE (-200 1950);
FORCEPROP 1 LASTPIN (-25 2050) $PN 2
J 0
(-63 2062);
DISPLAY 0.617021 (-63 2062);
PAINT ORANGE (-63 2062);
FORCEPROP 1 LASTPIN (-225 2050) $PN 1
J 0
(-213 2062);
DISPLAY 0.617021 (-213 2062);
PAINT ORANGE (-213 2062);
FORCEPROP 2 LAST SEC_TYPE 0402
J 0
(-175 2250);
DISPLAY 1.021277 (-175 2250);
PAINT ORANGE (-175 2250);
DISPLAY INVISIBLE (-175 2250);
FORCEPROP 2 LAST BOM_COST PROC_SIDEBAND
J 2
(-125 2050);
PAINT MONO (-125 2050);
DISPLAY INVISIBLE (-125 2050);
FORCEPROP 2 LAST CDS_LIB mstr_discrete
J 0
(-125 2050);
PAINT ORANGE (-125 2050);
DISPLAY INVISIBLE (-125 2050);
FORCEPROP 2 LAST SEC 1
J 0
(-175 2250);
DISPLAY 0.680851 (-175 2250);
PAINT MONO (-175 2250);
DISPLAY INVISIBLE (-175 2250);
FORCEPROP 2 LAST CDS_LOCATION R7D34
J 0
(-175 2100);
DISPLAY 0.617021 (-175 2100);
PAINT AQUA (-175 2100);
DISPLAY INVISIBLE (-175 2100);
FORCEPROP 1 LAST PATH I24
J 0
(-175 2200);
DISPLAY 0.978723 (-175 2200);
PAINT WHITE (-175 2200);
DISPLAY INVISIBLE (-175 2200);
FORCEPROP 2 LAST ROOM PROC_SIDEBAND
J 0
(-200 1975);
DISPLAY 0.617021 (-200 1975);
PAINT ORANGE (-200 1975);
DISPLAY INVISIBLE (-200 1975);
FORCEADD OFFPAGE..1
(-3225 2050);
FORCEPROP 2 LAST $XR0 21 
J 0
(-3476 2050);
DISPLAY 0.638298 (-3476 2050);
PAINT MONO (-3476 2050);
FORCEPROP 2 LAST CDS_LIB mstr_standard
J 0
(-3225 2050);
PAINT ORANGE (-3225 2050);
DISPLAY INVISIBLE (-3225 2050);
FORCEPROP 1 LAST OFFPAGE TRUE
J 0
(-2900 1925);
PAINT GREEN (-2900 1925);
DISPLAY INVISIBLE (-2900 1925);
FORCEPROP 1 LAST COMMENT_BODY TRUE
J 0
(-3100 1950);
DISPLAY 1.170213 (-3100 1950);
PAINT GREEN (-3100 1950);
DISPLAY INVISIBLE (-3100 1950);
FORCEPROP 2 LAST PATH I27
J 0
(-3425 2100);
DISPLAY 1.021277 (-3425 2100);
PAINT ORANGE (-3425 2100);
DISPLAY INVISIBLE (-3425 2100);
FORCEADD RES..1
(-100 1800);
FORCEPROP 1 LAST LOCATION R7D31
J 0
(-150 1850);
DISPLAY 0.617021 (-150 1850);
PAINT AQUA (-150 1850);
FORCEPROP 1 LAST PART_NUMBER G21796-074
J 0
(-50 1700);
DISPLAY 0.617021 (-50 1700);
PAINT BLUE (-50 1700);
FORCEPROP 1 LAST VALUE 33.2
J 2
(-125 1750);
DISPLAY 0.617021 (-125 1750);
PAINT SKYBLUE (-125 1750);
FORCEPROP 1 LAST TOLERANCE 1%
J 0
(-100 1750);
DISPLAY 0.617021 (-100 1750);
PAINT SKYBLUE (-100 1750);
FORCEPROP 1 LAST PACK_TYPE 0402
J 0
(0 1750);
DISPLAY 0.617021 (0 1750);
PAINT SKYBLUE (0 1750);
FORCEPROP 1 LAST MATERIAL CHIP
J 0
(-175 1700);
DISPLAY 0.617021 (-175 1700);
PAINT SKYBLUE (-175 1700);
FORCEPROP 1 LAST WATTAGE 1/16W
J 2
(-200 1700);
DISPLAY 0.617021 (-200 1700);
PAINT SKYBLUE (-200 1700);
FORCEPROP 1 LASTPIN (0 1800) $PN 2
J 0
(-38 1812);
DISPLAY 0.617021 (-38 1812);
PAINT ORANGE (-38 1812);
FORCEPROP 1 LASTPIN (-200 1800) $PN 1
J 0
(-188 1812);
DISPLAY 0.617021 (-188 1812);
PAINT ORANGE (-188 1812);
FORCEPROP 2 LAST SEC_TYPE 0402
J 0
(-150 2000);
DISPLAY 1.021277 (-150 2000);
PAINT ORANGE (-150 2000);
DISPLAY INVISIBLE (-150 2000);
FORCEPROP 2 LAST BOM_COST PROC_SIDEBAND
J 2
(-100 1800);
PAINT MONO (-100 1800);
DISPLAY INVISIBLE (-100 1800);
FORCEPROP 2 LAST CDS_LIB mstr_discrete
J 0
(-100 1800);
PAINT ORANGE (-100 1800);
DISPLAY INVISIBLE (-100 1800);
FORCEPROP 2 LAST SEC 1
J 0
(-150 2000);
DISPLAY 0.680851 (-150 2000);
PAINT MONO (-150 2000);
DISPLAY INVISIBLE (-150 2000);
FORCEPROP 2 LAST CDS_LOCATION R7D31
J 0
(-150 1850);
DISPLAY 0.617021 (-150 1850);
PAINT AQUA (-150 1850);
DISPLAY INVISIBLE (-150 1850);
FORCEPROP 1 LAST PATH I29
J 0
(-150 1950);
DISPLAY 0.978723 (-150 1950);
PAINT WHITE (-150 1950);
DISPLAY INVISIBLE (-150 1950);
FORCEPROP 2 LAST ROOM PROC_SIDEBAND
J 0
(-175 1725);
DISPLAY 0.617021 (-175 1725);
PAINT ORANGE (-175 1725);
DISPLAY INVISIBLE (-175 1725);
FORCEADD OFFPAGE..1
(-3050 4250);
FORCEPROP 2 LAST $XR0 55 
J 0
(-3301 4250);
DISPLAY 0.638298 (-3301 4250);
PAINT MONO (-3301 4250);
FORCEPROP 2 LAST CDS_LIB mstr_standard
J 0
(-3050 4250);
PAINT ORANGE (-3050 4250);
DISPLAY INVISIBLE (-3050 4250);
FORCEPROP 1 LAST OFFPAGE TRUE
J 0
(-2725 4125);
PAINT GREEN (-2725 4125);
DISPLAY INVISIBLE (-2725 4125);
FORCEPROP 1 LAST COMMENT_BODY TRUE
J 0
(-2925 4150);
DISPLAY 1.170213 (-2925 4150);
PAINT GREEN (-2925 4150);
DISPLAY INVISIBLE (-2925 4150);
FORCEPROP 2 LAST PATH I3
J 0
(-3000 4325);
DISPLAY 1.021277 (-3000 4325);
PAINT ORANGE (-3000 4325);
DISPLAY INVISIBLE (-3000 4325);
FORCEADD RES..1
(-100 1550);
FORCEPROP 1 LAST LOCATION R7D29
J 0
(-150 1600);
DISPLAY 0.617021 (-150 1600);
PAINT AQUA (-150 1600);
FORCEPROP 1 LAST PART_NUMBER G21796-074
J 0
(-25 1450);
DISPLAY 0.617021 (-25 1450);
PAINT BLUE (-25 1450);
FORCEPROP 1 LAST VALUE 33.2
J 2
(-125 1500);
DISPLAY 0.617021 (-125 1500);
PAINT SKYBLUE (-125 1500);
FORCEPROP 1 LAST TOLERANCE 1%
J 0
(-100 1500);
DISPLAY 0.617021 (-100 1500);
PAINT SKYBLUE (-100 1500);
FORCEPROP 1 LAST PACK_TYPE 0402
J 0
(0 1500);
DISPLAY 0.617021 (0 1500);
PAINT SKYBLUE (0 1500);
FORCEPROP 1 LAST MATERIAL CHIP
J 0
(-175 1450);
DISPLAY 0.617021 (-175 1450);
PAINT SKYBLUE (-175 1450);
FORCEPROP 1 LAST WATTAGE 1/16W
J 2
(-200 1450);
DISPLAY 0.617021 (-200 1450);
PAINT SKYBLUE (-200 1450);
FORCEPROP 1 LASTPIN (0 1550) $PN 2
J 0
(-38 1562);
DISPLAY 0.617021 (-38 1562);
PAINT ORANGE (-38 1562);
FORCEPROP 1 LASTPIN (-200 1550) $PN 1
J 0
(-188 1562);
DISPLAY 0.617021 (-188 1562);
PAINT ORANGE (-188 1562);
FORCEPROP 2 LAST BOM_COST PROC_SIDEBAND
J 2
(-100 1550);
PAINT MONO (-100 1550);
DISPLAY INVISIBLE (-100 1550);
FORCEPROP 2 LAST CDS_LIB mstr_discrete
J 0
(-100 1550);
PAINT ORANGE (-100 1550);
DISPLAY INVISIBLE (-100 1550);
FORCEPROP 2 LAST SEC_TYPE 0402
J 0
(-150 1750);
DISPLAY 1.021277 (-150 1750);
PAINT ORANGE (-150 1750);
DISPLAY INVISIBLE (-150 1750);
FORCEPROP 2 LAST SEC 1
J 0
(-150 1750);
DISPLAY 0.680851 (-150 1750);
PAINT MONO (-150 1750);
DISPLAY INVISIBLE (-150 1750);
FORCEPROP 2 LAST CDS_LOCATION R7D29
J 0
(-150 1600);
DISPLAY 0.617021 (-150 1600);
PAINT AQUA (-150 1600);
DISPLAY INVISIBLE (-150 1600);
FORCEPROP 1 LAST PATH I30
J 0
(-150 1700);
DISPLAY 0.978723 (-150 1700);
PAINT WHITE (-150 1700);
DISPLAY INVISIBLE (-150 1700);
FORCEPROP 2 LAST ROOM PROC_SIDEBAND
J 0
(-175 1475);
DISPLAY 0.617021 (-175 1475);
PAINT ORANGE (-175 1475);
DISPLAY INVISIBLE (-175 1475);
FORCEADD GTL2014..1
R 2
(-1750 2050);
FORCEPROP 1 LAST LOCATION U7D2
J 2
(-1350 2600);
DISPLAY 0.617021 (-1350 2600);
PAINT AQUA (-1350 2600);
FORCEPROP 1 LAST PART_NUMBER D66151-001
J 2
(-1350 1525);
DISPLAY 0.617021 (-1350 1525);
PAINT BLUE (-1350 1525);
FORCEPROP 1 LAST MATERIAL IC
J 2
(-1350 2550);
DISPLAY 0.617021 (-1350 2550);
PAINT SKYBLUE (-1350 2550);
FORCEPROP 2 LASTPIN (-1300 2300) $PN 4
J 0
(-1290 2310);
DISPLAY 0.617021 (-1290 2310);
PAINT ORANGE (-1290 2310);
FORCEPROP 2 LASTPIN (-1300 2350) $PN 14
J 0
(-1290 2360);
DISPLAY 0.617021 (-1290 2360);
PAINT ORANGE (-1290 2360);
FORCEPROP 2 LASTPIN (-2200 1750) $PN 11
J 2
(-2210 1760);
DISPLAY 0.617021 (-2210 1760);
PAINT ORANGE (-2210 1760);
FORCEPROP 2 LASTPIN (-2200 1700) $PN 8
J 2
(-2210 1710);
DISPLAY 0.617021 (-2210 1710);
PAINT ORANGE (-2210 1710);
FORCEPROP 2 LASTPIN (-2200 1650) $PN 7
J 2
(-2210 1660);
DISPLAY 0.617021 (-2210 1660);
PAINT ORANGE (-2210 1660);
FORCEPROP 2 LASTPIN (-1300 2200) $PN 1
J 0
(-1290 2210);
DISPLAY 0.617021 (-1290 2210);
PAINT ORANGE (-1290 2210);
FORCEPROP 2 LASTPIN (-2200 2050) $PN 6
J 2
(-2210 2060);
DISPLAY 0.617021 (-2210 2060);
PAINT ORANGE (-2210 2060);
FORCEPROP 2 LASTPIN (-2200 2000) $PN 5
J 2
(-2210 2010);
DISPLAY 0.617021 (-2210 2010);
PAINT ORANGE (-2210 2010);
FORCEPROP 2 LASTPIN (-2200 1950) $PN 3
J 2
(-2210 1960);
DISPLAY 0.617021 (-2210 1960);
PAINT ORANGE (-2210 1960);
FORCEPROP 2 LASTPIN (-2200 1900) $PN 2
J 2
(-2210 1910);
DISPLAY 0.617021 (-2210 1910);
PAINT ORANGE (-2210 1910);
FORCEPROP 2 LASTPIN (-1300 2050) $PN 9
J 0
(-1290 2060);
DISPLAY 0.617021 (-1290 2060);
PAINT ORANGE (-1290 2060);
FORCEPROP 2 LASTPIN (-1300 2000) $PN 10
J 0
(-1290 2010);
DISPLAY 0.617021 (-1290 2010);
PAINT ORANGE (-1290 2010);
FORCEPROP 2 LASTPIN (-1300 1950) $PN 12
J 0
(-1290 1960);
DISPLAY 0.617021 (-1290 1960);
PAINT ORANGE (-1290 1960);
FORCEPROP 2 LASTPIN (-1300 1900) $PN 13
J 0
(-1290 1910);
DISPLAY 0.617021 (-1290 1910);
PAINT ORANGE (-1290 1910);
FORCEPROP 1 LAST PACK_TYPE SM
J 2
(-1350 2650);
PAINT SKYBLUE (-1350 2650);
DISPLAY INVISIBLE (-1350 2650);
FORCEPROP 2 LAST CDS_LIB mstr_digital
J 0
(-1750 2050);
PAINT ORANGE (-1750 2050);
DISPLAY INVISIBLE (-1750 2050);
FORCEPROP 2 LAST BOM_COST PROC_SIDEBAND
J 2
(-1750 2050);
PAINT MONO (-1750 2050);
DISPLAY INVISIBLE (-1750 2050);
FORCEPROP 2 LAST SEC_TYPE SM
J 0
(-1350 2650);
DISPLAY 1.021277 (-1350 2650);
PAINT ORANGE (-1350 2650);
DISPLAY INVISIBLE (-1350 2650);
FORCEPROP 2 LAST SEC 1
J 0
(-1350 2650);
DISPLAY 0.680851 (-1350 2650);
PAINT MONO (-1350 2650);
DISPLAY INVISIBLE (-1350 2650);
FORCEPROP 2 LAST CDS_LOCATION U7D2
J 2
(-1350 2600);
DISPLAY 0.617021 (-1350 2600);
PAINT AQUA (-1350 2600);
DISPLAY INVISIBLE (-1350 2600);
FORCEPROP 1 LAST PATH I32
J 2
(-1750 2550);
PAINT GREEN (-1750 2550);
DISPLAY INVISIBLE (-1750 2550);
FORCEPROP 2 LAST ROOM PROC_SIDEBAND
J 2
(-1350 2700);
PAINT MONO (-1350 2700);
DISPLAY INVISIBLE (-1350 2700);
FORCEADD GND..1
(-2475 1525);
FORCEPROP 3 LASTPIN (-2475 1575) SIG_NAME GND\g
J 0
(-2465 1585);
DISPLAY 0.659574 (-2465 1585);
PAINT MONO (-2465 1585);
DISPLAY INVISIBLE (-2465 1585);
FORCEPROP 1 LAST VOLTAGE 0
J 0
(-2475 1525);
PAINT SKYBLUE (-2475 1525);
DISPLAY INVISIBLE (-2475 1525);
FORCEPROP 2 LAST CDS_LIB mstr_symbols
J 0
(-2475 1525);
PAINT ORANGE (-2475 1525);
DISPLAY INVISIBLE (-2475 1525);
FORCEPROP 1 LAST SIZE 1B
J 0
(-2400 1475);
DISPLAY 1.212766 (-2400 1475);
PAINT GREEN (-2400 1475);
DISPLAY INVISIBLE (-2400 1475);
FORCEPROP 1 LAST BODY_TYPE PLUMBING
J 0
(-2520 1482);
DISPLAY 0.340426 (-2520 1482);
PAINT GREEN (-2520 1482);
DISPLAY INVISIBLE (-2520 1482);
FORCEPROP 1 LAST PATH I33
J 0
(-2400 1525);
DISPLAY 0.872340 (-2400 1525);
PAINT AQUA (-2400 1525);
DISPLAY INVISIBLE (-2400 1525);
FORCEPROP 1 LAST HDL_POWER GND
J 0
(-2475 1675);
DISPLAY 1.212766 (-2475 1675);
PAINT GREEN (-2475 1675);
DISPLAY INVISIBLE (-2475 1675);
FORCEADD OFFPAGE..1
(-3225 1950);
FORCEPROP 2 LAST $XR0 22 
J 0
(-3476 1950);
DISPLAY 0.638298 (-3476 1950);
PAINT MONO (-3476 1950);
FORCEPROP 2 LAST CDS_LIB mstr_standard
J 0
(-3225 1950);
PAINT ORANGE (-3225 1950);
DISPLAY INVISIBLE (-3225 1950);
FORCEPROP 1 LAST OFFPAGE TRUE
J 0
(-2900 1825);
PAINT GREEN (-2900 1825);
DISPLAY INVISIBLE (-2900 1825);
FORCEPROP 1 LAST COMMENT_BODY TRUE
J 0
(-3100 1850);
DISPLAY 1.170213 (-3100 1850);
PAINT GREEN (-3100 1850);
DISPLAY INVISIBLE (-3100 1850);
FORCEPROP 2 LAST PATH I36
J 0
(-3425 2000);
DISPLAY 1.021277 (-3425 2000);
PAINT ORANGE (-3425 2000);
DISPLAY INVISIBLE (-3425 2000);
FORCEADD CAP_A..1
(-300 4825);
FORCEPROP 1 LAST LOCATION C3P49
J 0
(-250 4925);
DISPLAY 0.617021 (-250 4925);
PAINT AQUA (-250 4925);
FORCEPROP 1 LAST PART_NUMBER A36096-030
J 0
(-250 4675);
DISPLAY 0.617021 (-250 4675);
PAINT BLUE (-250 4675);
FORCEPROP 1 LAST VALUE 0.1UF
J 0
(-250 4875);
DISPLAY 0.617021 (-250 4875);
PAINT SKYBLUE (-250 4875);
FORCEPROP 1 LAST TOLERANCE 10%
J 0
(-250 4775);
DISPLAY 0.617021 (-250 4775);
PAINT SKYBLUE (-250 4775);
FORCEPROP 1 LAST PACK_TYPE 0402V
J 0
(-250 4625);
DISPLAY 0.617021 (-250 4625);
PAINT SKYBLUE (-250 4625);
FORCEPROP 1 LAST VOLTAGE 16V
J 0
(-250 4825);
DISPLAY 0.617021 (-250 4825);
PAINT SKYBLUE (-250 4825);
FORCEPROP 1 LAST MATERIAL X7R
J 0
(-250 4725);
DISPLAY 0.617021 (-250 4725);
PAINT SKYBLUE (-250 4725);
FORCEPROP 1 LASTPIN (-300 4925) $PN 1
J 0
(-290 4905);
DISPLAY 0.617021 (-290 4905);
PAINT MONO (-290 4905);
FORCEPROP 1 LASTPIN (-300 4725) $PN 2
J 0
(-290 4705);
DISPLAY 0.617021 (-290 4705);
PAINT MONO (-290 4705);
FORCEPROP 1 LAST PATH I37
J 0
(-250 4975);
DISPLAY 0.978723 (-250 4975);
PAINT WHITE (-250 4975);
DISPLAY INVISIBLE (-250 4975);
FORCEPROP 2 LAST ROOM PROC_SIDEBAND
J 0
(-250 4575);
DISPLAY 0.978723 (-250 4575);
PAINT ORANGE (-250 4575);
DISPLAY INVISIBLE (-250 4575);
FORCEPROP 2 LAST CDS_LOCATION C3P49
J 0
(-250 4925);
DISPLAY 0.617021 (-250 4925);
PAINT AQUA (-250 4925);
DISPLAY INVISIBLE (-250 4925);
FORCEPROP 2 LAST BOM_COST PROC_SIDEBAND
J 0
(-300 4825);
PAINT MONO (-300 4825);
DISPLAY INVISIBLE (-300 4825);
FORCEPROP 2 LAST CDS_LIB dev_discrete
J 0
(-300 4825);
PAINT ORANGE (-300 4825);
DISPLAY INVISIBLE (-300 4825);
FORCEPROP 2 LAST CDS_SEC 1
J 0
(-250 4975);
PAINT ORANGE (-250 4975);
DISPLAY INVISIBLE (-250 4975);
FORCEPROP 2 LAST SEC_TYPE 0402V
J 0
(-250 5025);
PAINT MONO (-250 5025);
DISPLAY INVISIBLE (-250 5025);
FORCEPROP 2 LAST SEC 1
J 0
(-250 5025);
DISPLAY 0.936170 (-250 5025);
PAINT MONO (-250 5025);
DISPLAY INVISIBLE (-250 5025);
FORCEADD RES..2
(125 4800);
FORCEPROP 1 LAST LOCATION R3P49
J 0
(170 4925);
DISPLAY 0.617021 (170 4925);
PAINT AQUA (170 4925);
FORCEPROP 1 LAST PART_NUMBER G21796-017
J 0
(165 4675);
DISPLAY 0.617021 (165 4675);
PAINT BLUE (165 4675);
FORCEPROP 1 LAST VALUE 100.0
J 0
(170 4875);
DISPLAY 0.617021 (170 4875);
PAINT SKYBLUE (170 4875);
FORCEPROP 1 LAST TOLERANCE 1%
J 0
(170 4825);
DISPLAY 0.617021 (170 4825);
PAINT SKYBLUE (170 4825);
FORCEPROP 1 LAST PACK_TYPE 0402
J 0
(165 4625);
DISPLAY 0.617021 (165 4625);
PAINT SKYBLUE (165 4625);
FORCEPROP 1 LAST MATERIAL CHIP
J 0
(165 4725);
DISPLAY 0.617021 (165 4725);
PAINT SKYBLUE (165 4725);
FORCEPROP 1 LAST WATTAGE 1/16W
J 0
(165 4775);
DISPLAY 0.617021 (165 4775);
PAINT SKYBLUE (165 4775);
FORCEPROP 1 LASTPIN (125 4700) $PN 2
J 0
(130 4710);
DISPLAY 0.617021 (130 4710);
PAINT MONO (130 4710);
FORCEPROP 1 LASTPIN (125 4900) $PN 1
J 0
(130 4862);
DISPLAY 0.617021 (130 4862);
PAINT MONO (130 4862);
FORCEPROP 2 LAST SEC_TYPE 0402
J 0
(175 5025);
PAINT MONO (175 5025);
DISPLAY INVISIBLE (175 5025);
FORCEPROP 2 LAST CDS_LIB mstr_discrete
J 2
(125 4800);
PAINT ORANGE (125 4800);
DISPLAY INVISIBLE (125 4800);
FORCEPROP 2 LAST BOM_COST PROC_SIDEBAND
J 0
(125 4800);
PAINT MONO (125 4800);
DISPLAY INVISIBLE (125 4800);
FORCEPROP 2 LAST SEC 1
J 0
(175 5025);
DISPLAY 0.936170 (175 5025);
PAINT MONO (175 5025);
DISPLAY INVISIBLE (175 5025);
FORCEPROP 2 LAST CDS_LOCATION R3P49
J 0
(170 4925);
DISPLAY 0.617021 (170 4925);
PAINT AQUA (170 4925);
DISPLAY INVISIBLE (170 4925);
FORCEPROP 1 LAST PATH I38
J 0
(175 4975);
DISPLAY 0.978723 (175 4975);
PAINT WHITE (175 4975);
DISPLAY INVISIBLE (175 4975);
FORCEPROP 2 LAST ROOM PROC_SIDEBAND
J 2
(425 4575);
DISPLAY 0.978723 (425 4575);
PAINT ORANGE (425 4575);
DISPLAY INVISIBLE (425 4575);
FORCEADD RES..2
(125 5200);
FORCEPROP 1 LAST LOCATION R3P45
J 0
(170 5325);
DISPLAY 0.617021 (170 5325);
PAINT AQUA (170 5325);
FORCEPROP 1 LAST PART_NUMBER G21796-047
J 0
(165 5075);
DISPLAY 0.617021 (165 5075);
PAINT BLUE (165 5075);
FORCEPROP 1 LAST VALUE 49.9
J 0
(170 5275);
DISPLAY 0.617021 (170 5275);
PAINT SKYBLUE (170 5275);
FORCEPROP 1 LAST TOLERANCE 1%
J 0
(170 5225);
DISPLAY 0.617021 (170 5225);
PAINT SKYBLUE (170 5225);
FORCEPROP 1 LAST PACK_TYPE 0402
J 0
(165 5025);
DISPLAY 0.617021 (165 5025);
PAINT SKYBLUE (165 5025);
FORCEPROP 1 LAST MATERIAL CHIP
J 0
(165 5125);
DISPLAY 0.617021 (165 5125);
PAINT SKYBLUE (165 5125);
FORCEPROP 1 LAST WATTAGE 1/16W
J 0
(165 5175);
DISPLAY 0.617021 (165 5175);
PAINT SKYBLUE (165 5175);
FORCEPROP 1 LASTPIN (125 5100) $PN 2
J 0
(130 5110);
DISPLAY 0.617021 (130 5110);
PAINT MONO (130 5110);
FORCEPROP 1 LASTPIN (125 5300) $PN 1
J 0
(130 5262);
DISPLAY 0.617021 (130 5262);
PAINT MONO (130 5262);
FORCEPROP 2 LAST SEC_TYPE 0402
J 0
(175 5425);
PAINT MONO (175 5425);
DISPLAY INVISIBLE (175 5425);
FORCEPROP 2 LAST CDS_LIB mstr_discrete
J 0
(125 5200);
PAINT ORANGE (125 5200);
DISPLAY INVISIBLE (125 5200);
FORCEPROP 2 LAST BOM_COST PROC_SIDEBAND
J 0
(125 5200);
PAINT MONO (125 5200);
DISPLAY INVISIBLE (125 5200);
FORCEPROP 2 LAST SEC 1
J 0
(175 5425);
DISPLAY 0.936170 (175 5425);
PAINT MONO (175 5425);
DISPLAY INVISIBLE (175 5425);
FORCEPROP 2 LAST CDS_LOCATION R3P45
J 0
(170 5325);
DISPLAY 0.617021 (170 5325);
PAINT AQUA (170 5325);
DISPLAY INVISIBLE (170 5325);
FORCEPROP 1 LAST PATH I39
J 0
(175 5375);
DISPLAY 0.978723 (175 5375);
PAINT WHITE (175 5375);
DISPLAY INVISIBLE (175 5375);
FORCEPROP 2 LAST ROOM PROC_SIDEBAND
J 0
(150 4975);
PAINT ORANGE (150 4975);
DISPLAY INVISIBLE (150 4975);
FORCEADD GND..1
(125 4450);
FORCEPROP 3 LASTPIN (125 4500) SIG_NAME GND\g
J 0
(135 4510);
DISPLAY 0.659574 (135 4510);
PAINT MONO (135 4510);
DISPLAY INVISIBLE (135 4510);
FORCEPROP 1 LAST VOLTAGE 0
J 0
(125 4450);
PAINT SKYBLUE (125 4450);
DISPLAY INVISIBLE (125 4450);
FORCEPROP 2 LAST CDS_LIB mstr_symbols
J 0
(125 4450);
PAINT ORANGE (125 4450);
DISPLAY INVISIBLE (125 4450);
FORCEPROP 1 LAST SIZE 1B
J 0
(200 4400);
DISPLAY 1.212766 (200 4400);
PAINT GREEN (200 4400);
DISPLAY INVISIBLE (200 4400);
FORCEPROP 1 LAST BODY_TYPE PLUMBING
J 0
(80 4407);
DISPLAY 0.340426 (80 4407);
PAINT GREEN (80 4407);
DISPLAY INVISIBLE (80 4407);
FORCEPROP 1 LAST PATH I41
J 0
(200 4450);
DISPLAY 0.872340 (200 4450);
PAINT AQUA (200 4450);
DISPLAY INVISIBLE (200 4450);
FORCEPROP 1 LAST HDL_POWER GND
J 0
(125 4600);
DISPLAY 1.212766 (125 4600);
PAINT GREEN (125 4600);
DISPLAY INVISIBLE (125 4600);
FORCEADD P3V3..1
(-1175 4950);
FORCEPROP 3 LASTPIN (-1175 4900) SIG_NAME P3V3\g
J 0
(-1165 4910);
DISPLAY 0.659574 (-1165 4910);
PAINT MONO (-1165 4910);
DISPLAY INVISIBLE (-1165 4910);
FORCEPROP 1 LAST VOLTAGE 3.3V
J 0
(-1220 4907);
DISPLAY 0.340426 (-1220 4907);
PAINT SKYBLUE (-1220 4907);
DISPLAY INVISIBLE (-1220 4907);
FORCEPROP 1 LAST SIZE 1B
J 0
(-1130 4972);
DISPLAY 0.340426 (-1130 4972);
PAINT GREEN (-1130 4972);
DISPLAY INVISIBLE (-1130 4972);
FORCEPROP 2 LAST CDS_LIB mstr_symbols
J 0
(-1175 4950);
PAINT ORANGE (-1175 4950);
DISPLAY INVISIBLE (-1175 4950);
FORCEPROP 1 LAST BODY_TYPE PLUMBING
J 0
(-1220 4907);
DISPLAY 0.340426 (-1220 4907);
PAINT GREEN (-1220 4907);
DISPLAY INVISIBLE (-1220 4907);
FORCEPROP 1 LAST PATH I42
J 0
(-1130 4952);
DISPLAY 0.340426 (-1130 4952);
PAINT GREEN (-1130 4952);
DISPLAY INVISIBLE (-1130 4952);
FORCEPROP 1 LAST HDL_POWER P3V3
J 0
(-1500 4825);
DISPLAY 0.872340 (-1500 4825);
PAINT ORANGE (-1500 4825);
DISPLAY INVISIBLE (-1500 4825);
FORCEADD RES..1
(-675 4400);
FORCEPROP 1 LAST LOCATION R3R1
J 0
(-725 4450);
DISPLAY 0.617021 (-725 4450);
PAINT AQUA (-725 4450);
FORCEPROP 1 LAST PART_NUMBER G21796-026
J 0
(-1150 4350);
DISPLAY 0.617021 (-1150 4350);
PAINT BLUE (-1150 4350);
FORCEPROP 1 LAST VALUE 1.00K
J 2
(-725 4350);
DISPLAY 0.617021 (-725 4350);
PAINT SKYBLUE (-725 4350);
FORCEPROP 1 LAST TOLERANCE 1%
J 0
(-600 4350);
DISPLAY 0.617021 (-600 4350);
PAINT SKYBLUE (-600 4350);
FORCEPROP 1 LAST PACK_TYPE 0402
J 0
(-500 4350);
DISPLAY 0.617021 (-500 4350);
PAINT SKYBLUE (-500 4350);
FORCEPROP 1 LAST MATERIAL CHIP
J 0
(-400 4450);
DISPLAY 0.617021 (-400 4450);
PAINT SKYBLUE (-400 4450);
FORCEPROP 1 LAST WATTAGE 1/16W
J 2
(-450 4450);
DISPLAY 0.617021 (-450 4450);
PAINT SKYBLUE (-450 4450);
FORCEPROP 1 LASTPIN (-575 4400) $PN 2
J 0
(-613 4412);
DISPLAY 0.617021 (-613 4412);
PAINT ORANGE (-613 4412);
FORCEPROP 1 LASTPIN (-775 4400) $PN 1
J 0
(-763 4412);
DISPLAY 0.617021 (-763 4412);
PAINT ORANGE (-763 4412);
FORCEPROP 2 LAST SEC_TYPE 0402
J 0
(-725 4600);
DISPLAY 1.021277 (-725 4600);
PAINT ORANGE (-725 4600);
DISPLAY INVISIBLE (-725 4600);
FORCEPROP 2 LAST CDS_LIB mstr_discrete
J 0
(-675 4400);
PAINT ORANGE (-675 4400);
DISPLAY INVISIBLE (-675 4400);
FORCEPROP 2 LAST BOM_COST PROC_SIDEBAND
J 0
(-675 4400);
PAINT MONO (-675 4400);
DISPLAY INVISIBLE (-675 4400);
FORCEPROP 2 LAST SEC 1
J 0
(-725 4600);
DISPLAY 0.680851 (-725 4600);
PAINT MONO (-725 4600);
DISPLAY INVISIBLE (-725 4600);
FORCEPROP 2 LAST CDS_LOCATION R3R1
J 0
(-725 4450);
DISPLAY 0.617021 (-725 4450);
PAINT AQUA (-725 4450);
DISPLAY INVISIBLE (-725 4450);
FORCEPROP 1 LAST PATH I46
J 0
(-725 4550);
DISPLAY 0.978723 (-725 4550);
PAINT WHITE (-725 4550);
DISPLAY INVISIBLE (-725 4550);
FORCEPROP 2 LAST ROOM PROC_SIDEBAND
J 0
(-725 4550);
PAINT PEACH (-725 4550);
DISPLAY INVISIBLE (-725 4550);
FORCEADD GND..1
(-300 4325);
FORCEPROP 3 LASTPIN (-300 4375) SIG_NAME GND\g
J 0
(-290 4385);
DISPLAY 0.659574 (-290 4385);
PAINT MONO (-290 4385);
DISPLAY INVISIBLE (-290 4385);
FORCEPROP 1 LAST VOLTAGE 0
J 0
(-300 4325);
PAINT SKYBLUE (-300 4325);
DISPLAY INVISIBLE (-300 4325);
FORCEPROP 2 LAST CDS_LIB mstr_symbols
J 0
(-300 4325);
PAINT ORANGE (-300 4325);
DISPLAY INVISIBLE (-300 4325);
FORCEPROP 1 LAST SIZE 1B
J 0
(-225 4275);
DISPLAY 1.170213 (-225 4275);
PAINT GREEN (-225 4275);
DISPLAY INVISIBLE (-225 4275);
FORCEPROP 1 LAST BODY_TYPE PLUMBING
J 0
(-345 4282);
DISPLAY 0.340426 (-345 4282);
PAINT GREEN (-345 4282);
DISPLAY INVISIBLE (-345 4282);
FORCEPROP 1 LAST PATH I47
J 0
(-225 4325);
DISPLAY 0.872340 (-225 4325);
PAINT AQUA (-225 4325);
DISPLAY INVISIBLE (-225 4325);
FORCEPROP 1 LAST HDL_POWER GND
J 0
(-300 4475);
DISPLAY 1.170213 (-300 4475);
PAINT GREEN (-300 4475);
DISPLAY INVISIBLE (-300 4475);
FORCEADD RES..2
(350 2525);
FORCEPROP 1 LAST LOCATION R7D32
J 0
(395 2650);
DISPLAY 0.617021 (395 2650);
PAINT AQUA (395 2650);
FORCEPROP 1 LAST PART_NUMBER G21796-017
J 0
(390 2400);
DISPLAY 0.617021 (390 2400);
PAINT BLUE (390 2400);
FORCEPROP 1 LAST VALUE 100.0
J 0
(395 2600);
DISPLAY 0.617021 (395 2600);
PAINT SKYBLUE (395 2600);
FORCEPROP 1 LAST TOLERANCE 1%
J 0
(395 2550);
DISPLAY 0.617021 (395 2550);
PAINT SKYBLUE (395 2550);
FORCEPROP 1 LAST PACK_TYPE 0402
J 0
(390 2350);
DISPLAY 0.617021 (390 2350);
PAINT SKYBLUE (390 2350);
FORCEPROP 1 LAST MATERIAL CHIP
J 0
(390 2450);
DISPLAY 0.617021 (390 2450);
PAINT SKYBLUE (390 2450);
FORCEPROP 1 LAST WATTAGE 1/16W
J 0
(390 2500);
DISPLAY 0.617021 (390 2500);
PAINT SKYBLUE (390 2500);
FORCEPROP 1 LASTPIN (350 2425) $PN 2
J 0
(355 2435);
DISPLAY 0.617021 (355 2435);
PAINT MONO (355 2435);
FORCEPROP 1 LASTPIN (350 2625) $PN 1
J 0
(355 2587);
DISPLAY 0.617021 (355 2587);
PAINT MONO (355 2587);
FORCEPROP 2 LAST CDS_LIB mstr_discrete
J 2
(350 2525);
PAINT ORANGE (350 2525);
DISPLAY INVISIBLE (350 2525);
FORCEPROP 2 LAST BOM_COST PROC_SIDEBAND
J 0
(350 2525);
PAINT MONO (350 2525);
DISPLAY INVISIBLE (350 2525);
FORCEPROP 2 LAST SEC_TYPE 0402
J 0
(400 2750);
DISPLAY 1.021277 (400 2750);
PAINT ORANGE (400 2750);
DISPLAY INVISIBLE (400 2750);
FORCEPROP 2 LAST SEC 1
J 0
(400 2750);
DISPLAY 0.680851 (400 2750);
PAINT MONO (400 2750);
DISPLAY INVISIBLE (400 2750);
FORCEPROP 2 LAST CDS_LOCATION R7D32
J 0
(395 2650);
DISPLAY 0.617021 (395 2650);
PAINT AQUA (395 2650);
DISPLAY INVISIBLE (395 2650);
FORCEPROP 1 LAST PATH I48
J 0
(400 2700);
DISPLAY 0.978723 (400 2700);
PAINT WHITE (400 2700);
DISPLAY INVISIBLE (400 2700);
FORCEPROP 2 LAST ROOM PROC_SIDEBAND
J 2
(650 2300);
DISPLAY 0.978723 (650 2300);
PAINT ORANGE (650 2300);
DISPLAY INVISIBLE (650 2300);
FORCEADD GND..1
(350 2175);
FORCEPROP 3 LASTPIN (350 2225) SIG_NAME GND\g
J 0
(360 2235);
DISPLAY 0.659574 (360 2235);
PAINT MONO (360 2235);
DISPLAY INVISIBLE (360 2235);
FORCEPROP 1 LAST VOLTAGE 0
J 0
(350 2175);
PAINT SKYBLUE (350 2175);
DISPLAY INVISIBLE (350 2175);
FORCEPROP 1 LAST SIZE 1B
J 0
(425 2125);
DISPLAY 1.212766 (425 2125);
PAINT GREEN (425 2125);
DISPLAY INVISIBLE (425 2125);
FORCEPROP 2 LAST CDS_LIB mstr_symbols
J 0
(350 2175);
PAINT ORANGE (350 2175);
DISPLAY INVISIBLE (350 2175);
FORCEPROP 1 LAST BODY_TYPE PLUMBING
J 0
(305 2132);
DISPLAY 0.340426 (305 2132);
PAINT GREEN (305 2132);
DISPLAY INVISIBLE (305 2132);
FORCEPROP 1 LAST PATH I49
J 0
(425 2175);
DISPLAY 0.872340 (425 2175);
PAINT AQUA (425 2175);
DISPLAY INVISIBLE (425 2175);
FORCEPROP 1 LAST HDL_POWER GND
J 0
(350 2325);
DISPLAY 1.212766 (350 2325);
PAINT GREEN (350 2325);
DISPLAY INVISIBLE (350 2325);
FORCEADD OFFPAGE..1
(-3050 4150);
FORCEPROP 2 LAST $XR0 56 
J 0
(-3301 4150);
DISPLAY 0.638298 (-3301 4150);
PAINT MONO (-3301 4150);
FORCEPROP 2 LAST CDS_LIB mstr_standard
J 0
(-3050 4150);
PAINT ORANGE (-3050 4150);
DISPLAY INVISIBLE (-3050 4150);
FORCEPROP 1 LAST OFFPAGE TRUE
J 0
(-2725 4025);
PAINT GREEN (-2725 4025);
DISPLAY INVISIBLE (-2725 4025);
FORCEPROP 1 LAST COMMENT_BODY TRUE
J 0
(-2925 4050);
DISPLAY 1.170213 (-2925 4050);
PAINT GREEN (-2925 4050);
DISPLAY INVISIBLE (-2925 4050);
FORCEPROP 2 LAST PATH I5
J 0
(-3000 4225);
DISPLAY 1.021277 (-3000 4225);
PAINT ORANGE (-3000 4225);
DISPLAY INVISIBLE (-3000 4225);
FORCEADD PVCCIO_CPU0..1
(350 3275);
FORCEPROP 3 LASTPIN (350 3225) SIG_NAME PVCCIO_CPU0\g
J 0
(360 3235);
DISPLAY 0.659574 (360 3235);
PAINT MONO (360 3235);
DISPLAY INVISIBLE (360 3235);
FORCEPROP 1 LAST VOLTAGE 1.1V
J 0
(305 3232);
DISPLAY 0.340426 (305 3232);
PAINT SKYBLUE (305 3232);
DISPLAY INVISIBLE (305 3232);
FORCEPROP 2 LAST CDS_LIB mstr_symbols
J 0
(350 3275);
PAINT ORANGE (350 3275);
DISPLAY INVISIBLE (350 3275);
FORCEPROP 1 LAST BODY_TYPE PLUMBING
J 0
(305 3232);
DISPLAY 0.340426 (305 3232);
PAINT GREEN (305 3232);
DISPLAY INVISIBLE (305 3232);
FORCEPROP 1 LAST PATH I50
J 0
(400 3300);
DISPLAY 0.872340 (400 3300);
PAINT AQUA (400 3300);
DISPLAY INVISIBLE (400 3300);
FORCEPROP 1 LAST HDL_POWER PVCCIO_CPU0
J 1
(350 3325);
DISPLAY 0.872340 (350 3325);
PAINT GREEN (350 3325);
DISPLAY INVISIBLE (350 3325);
FORCEADD RES..2
(350 3050);
FORCEPROP 1 LAST LOCATION R7D33
J 0
(395 3175);
DISPLAY 0.617021 (395 3175);
PAINT AQUA (395 3175);
FORCEPROP 1 LAST PART_NUMBER G21796-047
J 0
(390 2925);
DISPLAY 0.617021 (390 2925);
PAINT BLUE (390 2925);
FORCEPROP 1 LAST VALUE 49.9
J 0
(395 3125);
DISPLAY 0.617021 (395 3125);
PAINT SKYBLUE (395 3125);
FORCEPROP 1 LAST TOLERANCE 1%
J 0
(395 3075);
DISPLAY 0.617021 (395 3075);
PAINT SKYBLUE (395 3075);
FORCEPROP 1 LAST PACK_TYPE 0402
J 0
(390 2875);
DISPLAY 0.617021 (390 2875);
PAINT SKYBLUE (390 2875);
FORCEPROP 1 LAST MATERIAL CHIP
J 0
(390 2975);
DISPLAY 0.617021 (390 2975);
PAINT SKYBLUE (390 2975);
FORCEPROP 1 LAST WATTAGE 1/16W
J 0
(390 3025);
DISPLAY 0.617021 (390 3025);
PAINT SKYBLUE (390 3025);
FORCEPROP 1 LASTPIN (350 2950) $PN 2
J 0
(355 2960);
DISPLAY 0.617021 (355 2960);
PAINT MONO (355 2960);
FORCEPROP 1 LASTPIN (350 3150) $PN 1
J 0
(355 3112);
DISPLAY 0.617021 (355 3112);
PAINT MONO (355 3112);
FORCEPROP 2 LAST CDS_LIB mstr_discrete
J 0
(350 3050);
PAINT ORANGE (350 3050);
DISPLAY INVISIBLE (350 3050);
FORCEPROP 2 LAST BOM_COST PROC_SIDEBAND
J 0
(350 3050);
PAINT MONO (350 3050);
DISPLAY INVISIBLE (350 3050);
FORCEPROP 2 LAST SEC_TYPE 0402
J 0
(400 3275);
PAINT MONO (400 3275);
DISPLAY INVISIBLE (400 3275);
FORCEPROP 2 LAST SEC 1
J 0
(400 3275);
DISPLAY 0.936170 (400 3275);
PAINT MONO (400 3275);
DISPLAY INVISIBLE (400 3275);
FORCEPROP 2 LAST CDS_LOCATION R7D33
J 0
(395 3175);
DISPLAY 0.617021 (395 3175);
PAINT AQUA (395 3175);
DISPLAY INVISIBLE (395 3175);
FORCEPROP 1 LAST PATH I51
J 0
(400 3225);
DISPLAY 0.978723 (400 3225);
PAINT WHITE (400 3225);
DISPLAY INVISIBLE (400 3225);
FORCEPROP 2 LAST ROOM PROC_SIDEBAND
J 0
(375 2825);
PAINT ORANGE (375 2825);
DISPLAY INVISIBLE (375 2825);
FORCEADD CAP_A..1
(-75 2550);
FORCEPROP 1 LAST LOCATION C7D5
J 0
(-25 2650);
DISPLAY 0.617021 (-25 2650);
PAINT AQUA (-25 2650);
FORCEPROP 1 LAST PART_NUMBER A36096-030
J 0
(-25 2400);
DISPLAY 0.617021 (-25 2400);
PAINT BLUE (-25 2400);
FORCEPROP 1 LAST VALUE 0.1UF
J 0
(-25 2600);
DISPLAY 0.617021 (-25 2600);
PAINT SKYBLUE (-25 2600);
FORCEPROP 1 LAST TOLERANCE 10%
J 0
(-25 2500);
DISPLAY 0.617021 (-25 2500);
PAINT SKYBLUE (-25 2500);
FORCEPROP 1 LAST PACK_TYPE 0402V
J 0
(-25 2350);
DISPLAY 0.617021 (-25 2350);
PAINT SKYBLUE (-25 2350);
FORCEPROP 1 LAST VOLTAGE 16V
J 0
(-25 2550);
DISPLAY 0.617021 (-25 2550);
PAINT SKYBLUE (-25 2550);
FORCEPROP 1 LAST MATERIAL X7R
J 0
(-25 2450);
DISPLAY 0.617021 (-25 2450);
PAINT SKYBLUE (-25 2450);
FORCEPROP 1 LASTPIN (-75 2650) $PN 1
J 0
(-65 2630);
DISPLAY 0.617021 (-65 2630);
PAINT MONO (-65 2630);
FORCEPROP 1 LASTPIN (-75 2450) $PN 2
J 0
(-65 2430);
DISPLAY 0.617021 (-65 2430);
PAINT MONO (-65 2430);
FORCEPROP 1 LAST PATH I52
J 0
(-25 2700);
DISPLAY 0.978723 (-25 2700);
PAINT WHITE (-25 2700);
DISPLAY INVISIBLE (-25 2700);
FORCEPROP 2 LAST ROOM PROC_SIDEBAND
J 0
(-25 2300);
DISPLAY 0.978723 (-25 2300);
PAINT ORANGE (-25 2300);
DISPLAY INVISIBLE (-25 2300);
FORCEPROP 2 LAST CDS_LOCATION C7D5
J 0
(-25 2650);
DISPLAY 0.617021 (-25 2650);
PAINT AQUA (-25 2650);
DISPLAY INVISIBLE (-25 2650);
FORCEPROP 2 LAST BOM_COST PROC_SIDEBAND
J 0
(-75 2550);
PAINT MONO (-75 2550);
DISPLAY INVISIBLE (-75 2550);
FORCEPROP 2 LAST CDS_LIB dev_discrete
J 0
(-75 2550);
PAINT ORANGE (-75 2550);
DISPLAY INVISIBLE (-75 2550);
FORCEPROP 2 LAST CDS_SEC 1
J 0
(-25 2700);
PAINT ORANGE (-25 2700);
DISPLAY INVISIBLE (-25 2700);
FORCEPROP 2 LAST SEC_TYPE 0402V
J 0
(-25 2750);
PAINT MONO (-25 2750);
DISPLAY INVISIBLE (-25 2750);
FORCEPROP 2 LAST SEC 1
J 0
(-25 2750);
DISPLAY 0.936170 (-25 2750);
PAINT MONO (-25 2750);
DISPLAY INVISIBLE (-25 2750);
FORCEADD GND..1
(-225 2125);
FORCEPROP 3 LASTPIN (-225 2175) SIG_NAME GND\g
J 0
(-215 2185);
DISPLAY 0.659574 (-215 2185);
PAINT MONO (-215 2185);
DISPLAY INVISIBLE (-215 2185);
FORCEPROP 1 LAST VOLTAGE 0
J 0
(-225 2125);
PAINT SKYBLUE (-225 2125);
DISPLAY INVISIBLE (-225 2125);
FORCEPROP 2 LAST CDS_LIB mstr_symbols
J 0
(-225 2125);
PAINT ORANGE (-225 2125);
DISPLAY INVISIBLE (-225 2125);
FORCEPROP 1 LAST SIZE 1B
J 0
(-150 2075);
DISPLAY 1.170213 (-150 2075);
PAINT GREEN (-150 2075);
DISPLAY INVISIBLE (-150 2075);
FORCEPROP 1 LAST BODY_TYPE PLUMBING
J 0
(-270 2082);
DISPLAY 0.340426 (-270 2082);
PAINT GREEN (-270 2082);
DISPLAY INVISIBLE (-270 2082);
FORCEPROP 1 LAST PATH I53
J 0
(-150 2125);
DISPLAY 0.872340 (-150 2125);
PAINT AQUA (-150 2125);
DISPLAY INVISIBLE (-150 2125);
FORCEPROP 1 LAST HDL_POWER GND
J 0
(-225 2275);
DISPLAY 1.170213 (-225 2275);
PAINT GREEN (-225 2275);
DISPLAY INVISIBLE (-225 2275);
FORCEADD RES..1
(-600 2200);
FORCEPROP 1 LAST LOCATION R7D26
J 0
(-650 2250);
DISPLAY 0.617021 (-650 2250);
PAINT AQUA (-650 2250);
FORCEPROP 1 LAST PART_NUMBER G21796-026
J 0
(-1075 2150);
DISPLAY 0.617021 (-1075 2150);
PAINT BLUE (-1075 2150);
FORCEPROP 1 LAST VALUE 1.00K
J 2
(-650 2150);
DISPLAY 0.617021 (-650 2150);
PAINT SKYBLUE (-650 2150);
FORCEPROP 1 LAST TOLERANCE 1%
J 0
(-525 2150);
DISPLAY 0.617021 (-525 2150);
PAINT SKYBLUE (-525 2150);
FORCEPROP 1 LAST PACK_TYPE 0402
J 0
(-425 2150);
DISPLAY 0.617021 (-425 2150);
PAINT SKYBLUE (-425 2150);
FORCEPROP 1 LAST MATERIAL CHIP
J 0
(-325 2250);
DISPLAY 0.617021 (-325 2250);
PAINT SKYBLUE (-325 2250);
FORCEPROP 1 LAST WATTAGE 1/16W
J 2
(-375 2250);
DISPLAY 0.617021 (-375 2250);
PAINT SKYBLUE (-375 2250);
FORCEPROP 1 LASTPIN (-500 2200) $PN 2
J 0
(-538 2212);
DISPLAY 0.617021 (-538 2212);
PAINT ORANGE (-538 2212);
FORCEPROP 1 LASTPIN (-700 2200) $PN 1
J 0
(-688 2212);
DISPLAY 0.617021 (-688 2212);
PAINT ORANGE (-688 2212);
FORCEPROP 2 LAST BOM_COST PROC_SIDEBAND
J 0
(-600 2200);
PAINT MONO (-600 2200);
DISPLAY INVISIBLE (-600 2200);
FORCEPROP 2 LAST CDS_LIB mstr_discrete
J 0
(-600 2200);
PAINT ORANGE (-600 2200);
DISPLAY INVISIBLE (-600 2200);
FORCEPROP 2 LAST SEC_TYPE 0402
J 0
(-650 2400);
DISPLAY 1.021277 (-650 2400);
PAINT ORANGE (-650 2400);
DISPLAY INVISIBLE (-650 2400);
FORCEPROP 2 LAST SEC 1
J 0
(-650 2400);
DISPLAY 0.680851 (-650 2400);
PAINT MONO (-650 2400);
DISPLAY INVISIBLE (-650 2400);
FORCEPROP 2 LAST CDS_LOCATION R7D26
J 0
(-650 2250);
DISPLAY 0.617021 (-650 2250);
PAINT AQUA (-650 2250);
DISPLAY INVISIBLE (-650 2250);
FORCEPROP 1 LAST PATH I54
J 0
(-650 2350);
DISPLAY 0.978723 (-650 2350);
PAINT WHITE (-650 2350);
DISPLAY INVISIBLE (-650 2350);
FORCEPROP 2 LAST ROOM PROC_SIDEBAND
J 0
(-650 2350);
PAINT PEACH (-650 2350);
DISPLAY INVISIBLE (-650 2350);
FORCEADD P3V3..1
(-1050 2750);
FORCEPROP 3 LASTPIN (-1050 2700) SIG_NAME P3V3\g
J 0
(-1040 2710);
DISPLAY 0.659574 (-1040 2710);
PAINT MONO (-1040 2710);
DISPLAY INVISIBLE (-1040 2710);
FORCEPROP 1 LAST VOLTAGE 3.3V
J 0
(-1095 2707);
DISPLAY 0.340426 (-1095 2707);
PAINT SKYBLUE (-1095 2707);
DISPLAY INVISIBLE (-1095 2707);
FORCEPROP 2 LAST CDS_LIB mstr_symbols
J 0
(-1050 2750);
PAINT ORANGE (-1050 2750);
DISPLAY INVISIBLE (-1050 2750);
FORCEPROP 1 LAST SIZE 1B
J 0
(-1005 2772);
DISPLAY 0.340426 (-1005 2772);
PAINT GREEN (-1005 2772);
DISPLAY INVISIBLE (-1005 2772);
FORCEPROP 1 LAST BODY_TYPE PLUMBING
J 0
(-1095 2707);
DISPLAY 0.340426 (-1095 2707);
PAINT GREEN (-1095 2707);
DISPLAY INVISIBLE (-1095 2707);
FORCEPROP 1 LAST PATH I58
J 0
(-1005 2752);
DISPLAY 0.340426 (-1005 2752);
PAINT GREEN (-1005 2752);
DISPLAY INVISIBLE (-1005 2752);
FORCEPROP 1 LAST HDL_POWER P3V3
J 0
(-1375 2625);
DISPLAY 0.872340 (-1375 2625);
PAINT ORANGE (-1375 2625);
DISPLAY INVISIBLE (-1375 2625);
FORCEADD OFFPAGE..1
(-3050 4100);
FORCEPROP 2 LAST $XR0 118 
J 0
(-3332 4100);
DISPLAY 0.638298 (-3332 4100);
PAINT MONO (-3332 4100);
FORCEPROP 2 LAST CDS_LIB mstr_standard
J 0
(-3050 4100);
PAINT ORANGE (-3050 4100);
DISPLAY INVISIBLE (-3050 4100);
FORCEPROP 1 LAST OFFPAGE TRUE
J 0
(-2725 3975);
PAINT GREEN (-2725 3975);
DISPLAY INVISIBLE (-2725 3975);
FORCEPROP 1 LAST COMMENT_BODY TRUE
J 0
(-2925 4000);
DISPLAY 1.170213 (-2925 4000);
PAINT GREEN (-2925 4000);
DISPLAY INVISIBLE (-2925 4000);
FORCEPROP 2 LAST PATH I59
J 0
(-3325 4150);
DISPLAY 1.021277 (-3325 4150);
PAINT ORANGE (-3325 4150);
DISPLAY INVISIBLE (-3325 4150);
FORCEADD OFFPAGE..5
R 2
(1050 3550);
FORCEPROP 2 LAST $XR0 191 
J 0
(1239 3550);
DISPLAY 0.638298 (1239 3550);
PAINT MONO (1239 3550);
FORCEPROP 2 LAST CDS_LIB mstr_standard
J 0
(1050 3550);
PAINT ORANGE (1050 3550);
DISPLAY INVISIBLE (1050 3550);
FORCEPROP 1 LAST OFFPAGE TRUE
J 2
(725 3425);
PAINT GREEN (725 3425);
DISPLAY INVISIBLE (725 3425);
FORCEPROP 1 LAST COMMENT_BODY TRUE
J 2
(950 3475);
DISPLAY 1.170213 (950 3475);
PAINT GREEN (950 3475);
DISPLAY INVISIBLE (950 3475);
FORCEPROP 2 LAST PATH I60
J 0
(1250 3600);
DISPLAY 1.021277 (1250 3600);
PAINT ORANGE (1250 3600);
DISPLAY INVISIBLE (1250 3600);
FORCEADD RES..1
(-125 3550);
FORCEPROP 1 LAST LOCATION R3R3
J 0
(-175 3600);
DISPLAY 0.617021 (-175 3600);
PAINT AQUA (-175 3600);
FORCEPROP 1 LAST PART_NUMBER G21796-074
J 0
(150 3450);
DISPLAY 0.617021 (150 3450);
PAINT BLUE (150 3450);
FORCEPROP 1 LAST VALUE 33.2
J 2
(-150 3450);
DISPLAY 0.617021 (-150 3450);
PAINT SKYBLUE (-150 3450);
FORCEPROP 1 LAST TOLERANCE 1%
J 0
(-125 3450);
DISPLAY 0.617021 (-125 3450);
PAINT SKYBLUE (-125 3450);
FORCEPROP 1 LAST PACK_TYPE 0402
J 0
(0 3450);
DISPLAY 0.617021 (0 3450);
PAINT SKYBLUE (0 3450);
FORCEPROP 1 LAST MATERIAL CHIP
J 0
(-325 3450);
DISPLAY 0.617021 (-325 3450);
PAINT SKYBLUE (-325 3450);
FORCEPROP 1 LAST WATTAGE 1/16W
J 2
(-350 3450);
DISPLAY 0.617021 (-350 3450);
PAINT SKYBLUE (-350 3450);
FORCEPROP 1 LASTPIN (-25 3550) $PN 2
J 0
(-63 3562);
DISPLAY 0.617021 (-63 3562);
PAINT ORANGE (-63 3562);
FORCEPROP 1 LASTPIN (-225 3550) $PN 1
J 0
(-213 3562);
DISPLAY 0.617021 (-213 3562);
PAINT ORANGE (-213 3562);
FORCEPROP 2 LAST SEC_TYPE 0402
J 0
(-175 3750);
DISPLAY 1.021277 (-175 3750);
PAINT ORANGE (-175 3750);
DISPLAY INVISIBLE (-175 3750);
FORCEPROP 2 LAST BOM_COST PROC_SIDEBAND
J 2
(-125 3550);
PAINT MONO (-125 3550);
DISPLAY INVISIBLE (-125 3550);
FORCEPROP 2 LAST CDS_LIB mstr_discrete
J 0
(-125 3550);
PAINT ORANGE (-125 3550);
DISPLAY INVISIBLE (-125 3550);
FORCEPROP 2 LAST SEC 1
J 0
(-175 3750);
DISPLAY 0.680851 (-175 3750);
PAINT MONO (-175 3750);
DISPLAY INVISIBLE (-175 3750);
FORCEPROP 2 LAST CDS_LOCATION R3R3
J 0
(-175 3600);
DISPLAY 0.617021 (-175 3600);
PAINT AQUA (-175 3600);
DISPLAY INVISIBLE (-175 3600);
FORCEPROP 1 LAST PATH I61
J 0
(-175 3700);
DISPLAY 0.978723 (-175 3700);
PAINT WHITE (-175 3700);
DISPLAY INVISIBLE (-175 3700);
FORCEPROP 2 LAST ROOM PROC_SIDEBAND
J 0
(-200 3475);
DISPLAY 0.617021 (-200 3475);
PAINT ORANGE (-200 3475);
DISPLAY INVISIBLE (-200 3475);
FORCEADD OFFPAGE..1
(-5125 1550);
FORCEPROP 2 LAST $XR0 21 
J 0
(-5346 1550);
DISPLAY 0.638298 (-5346 1550);
PAINT MONO (-5346 1550);
FORCEPROP 2 LAST CDS_LIB mstr_standard
J 0
(-5125 1550);
PAINT ORANGE (-5125 1550);
DISPLAY INVISIBLE (-5125 1550);
FORCEPROP 1 LAST OFFPAGE TRUE
J 0
(-4800 1425);
PAINT GREEN (-4800 1425);
DISPLAY INVISIBLE (-4800 1425);
FORCEPROP 1 LAST COMMENT_BODY TRUE
J 0
(-5000 1450);
DISPLAY 1.170213 (-5000 1450);
PAINT GREEN (-5000 1450);
DISPLAY INVISIBLE (-5000 1450);
FORCEPROP 2 LAST PATH I62
J 0
(-5375 1600);
DISPLAY 1.021277 (-5375 1600);
PAINT ORANGE (-5375 1600);
DISPLAY INVISIBLE (-5375 1600);
FORCEADD OFFPAGE..1
(-5125 1275);
FORCEPROP 2 LAST $XR0 55 
J 0
(-5346 1275);
DISPLAY 0.638298 (-5346 1275);
PAINT MONO (-5346 1275);
FORCEPROP 2 LAST CDS_LIB mstr_standard
J 0
(-5125 1275);
PAINT ORANGE (-5125 1275);
DISPLAY INVISIBLE (-5125 1275);
FORCEPROP 1 LAST OFFPAGE TRUE
J 0
(-4800 1150);
PAINT GREEN (-4800 1150);
DISPLAY INVISIBLE (-4800 1150);
FORCEPROP 1 LAST COMMENT_BODY TRUE
J 0
(-5000 1175);
DISPLAY 1.170213 (-5000 1175);
PAINT GREEN (-5000 1175);
DISPLAY INVISIBLE (-5000 1175);
FORCEPROP 2 LAST PATH I63
J 0
(-5375 1325);
DISPLAY 1.021277 (-5375 1325);
PAINT ORANGE (-5375 1325);
DISPLAY INVISIBLE (-5375 1325);
FORCEADD RES..2
R 2
(-4600 1825);
FORCEPROP 1 LAST LOCATION R6D9
J 2
(-4645 1950);
DISPLAY 0.617021 (-4645 1950);
PAINT AQUA (-4645 1950);
FORCEPROP 1 LAST PART_NUMBER G21796-009
J 2
(-4640 1700);
DISPLAY 0.617021 (-4640 1700);
PAINT BLUE (-4640 1700);
FORCEPROP 1 LAST VALUE 150.0
J 2
(-4645 1900);
DISPLAY 0.617021 (-4645 1900);
PAINT SKYBLUE (-4645 1900);
FORCEPROP 1 LAST TOLERANCE 1%
J 2
(-4645 1850);
DISPLAY 0.617021 (-4645 1850);
PAINT SKYBLUE (-4645 1850);
FORCEPROP 1 LAST PACK_TYPE 0402
J 2
(-4640 1650);
DISPLAY 0.617021 (-4640 1650);
PAINT SKYBLUE (-4640 1650);
FORCEPROP 1 LAST MATERIAL CHIP
J 2
(-4640 1750);
DISPLAY 0.617021 (-4640 1750);
PAINT SKYBLUE (-4640 1750);
FORCEPROP 1 LAST WATTAGE 1/16W
J 2
(-4640 1800);
DISPLAY 0.617021 (-4640 1800);
PAINT SKYBLUE (-4640 1800);
FORCEPROP 1 LASTPIN (-4600 1725) $PN 2
J 2
(-4605 1735);
DISPLAY 0.617021 (-4605 1735);
PAINT ORANGE (-4605 1735);
FORCEPROP 1 LASTPIN (-4600 1925) $PN 1
J 2
(-4605 1887);
DISPLAY 0.617021 (-4605 1887);
PAINT ORANGE (-4605 1887);
FORCEPROP 2 LAST SEC_TYPE 0402
J 0
(-4650 2050);
DISPLAY 1.021277 (-4650 2050);
PAINT ORANGE (-4650 2050);
DISPLAY INVISIBLE (-4650 2050);
FORCEPROP 2 LAST BOM_COST PROC_SIDEBAND
J 2
(-4600 1825);
PAINT MONO (-4600 1825);
DISPLAY INVISIBLE (-4600 1825);
FORCEPROP 2 LAST CDS_LIB mstr_discrete
J 0
(-4600 1825);
PAINT ORANGE (-4600 1825);
DISPLAY INVISIBLE (-4600 1825);
FORCEPROP 2 LAST SEC 1
J 0
(-4650 2050);
DISPLAY 0.680851 (-4650 2050);
PAINT MONO (-4650 2050);
DISPLAY INVISIBLE (-4650 2050);
FORCEPROP 2 LAST CDS_LOCATION R6D9
J 2
(-4645 1950);
DISPLAY 0.617021 (-4645 1950);
PAINT AQUA (-4645 1950);
DISPLAY INVISIBLE (-4645 1950);
FORCEPROP 1 LAST PATH I64
J 2
(-4650 2000);
DISPLAY 0.978723 (-4650 2000);
PAINT WHITE (-4650 2000);
DISPLAY INVISIBLE (-4650 2000);
FORCEPROP 2 LAST ROOM PROC_SIDEBAND
J 2
(-4625 1600);
PAINT ORANGE (-4625 1600);
DISPLAY INVISIBLE (-4625 1600);
FORCEADD RES..2
(-4275 1800);
FORCEPROP 1 LAST LOCATION R7P27
J 0
(-4230 1925);
DISPLAY 0.617021 (-4230 1925);
PAINT AQUA (-4230 1925);
FORCEPROP 1 LAST PART_NUMBER G21796-009
J 0
(-4235 1675);
DISPLAY 0.617021 (-4235 1675);
PAINT BLUE (-4235 1675);
FORCEPROP 1 LAST VALUE 150.0
J 0
(-4230 1875);
DISPLAY 0.617021 (-4230 1875);
PAINT SKYBLUE (-4230 1875);
FORCEPROP 1 LAST TOLERANCE 1%
J 0
(-4230 1825);
DISPLAY 0.617021 (-4230 1825);
PAINT SKYBLUE (-4230 1825);
FORCEPROP 1 LAST PACK_TYPE 0402
J 0
(-4235 1625);
DISPLAY 0.617021 (-4235 1625);
PAINT SKYBLUE (-4235 1625);
FORCEPROP 1 LAST MATERIAL CHIP
J 0
(-4235 1725);
DISPLAY 0.617021 (-4235 1725);
PAINT SKYBLUE (-4235 1725);
FORCEPROP 1 LAST WATTAGE 1/16W
J 0
(-4235 1775);
DISPLAY 0.617021 (-4235 1775);
PAINT SKYBLUE (-4235 1775);
FORCEPROP 1 LASTPIN (-4275 1700) $PN 2
J 0
(-4270 1710);
DISPLAY 0.617021 (-4270 1710);
PAINT ORANGE (-4270 1710);
FORCEPROP 1 LASTPIN (-4275 1900) $PN 1
J 0
(-4270 1862);
DISPLAY 0.617021 (-4270 1862);
PAINT ORANGE (-4270 1862);
FORCEPROP 2 LAST CDS_LIB mstr_discrete
J 0
(-4275 1800);
PAINT ORANGE (-4275 1800);
DISPLAY INVISIBLE (-4275 1800);
FORCEPROP 2 LAST BOM_COST PROC_SIDEBAND
J 0
(-4275 1800);
PAINT MONO (-4275 1800);
DISPLAY INVISIBLE (-4275 1800);
FORCEPROP 2 LAST SEC_TYPE 0402
J 0
(-4225 2025);
DISPLAY 1.021277 (-4225 2025);
PAINT ORANGE (-4225 2025);
DISPLAY INVISIBLE (-4225 2025);
FORCEPROP 2 LAST SEC 1
J 0
(-4225 2025);
DISPLAY 0.680851 (-4225 2025);
PAINT MONO (-4225 2025);
DISPLAY INVISIBLE (-4225 2025);
FORCEPROP 2 LAST CDS_LOCATION R7P27
J 0
(-4230 1925);
DISPLAY 0.617021 (-4230 1925);
PAINT AQUA (-4230 1925);
DISPLAY INVISIBLE (-4230 1925);
FORCEPROP 1 LAST PATH I65
J 0
(-4225 1975);
DISPLAY 0.978723 (-4225 1975);
PAINT WHITE (-4225 1975);
DISPLAY INVISIBLE (-4225 1975);
FORCEPROP 2 LAST ROOM PROC_SIDEBAND
J 0
(-4250 1575);
PAINT ORANGE (-4250 1575);
DISPLAY INVISIBLE (-4250 1575);
FORCEADD PVCCIO_CPU0..1
(-4600 2050);
FORCEPROP 3 LASTPIN (-4600 2000) SIG_NAME PVCCIO_CPU0\g
J 0
(-4590 2010);
DISPLAY 0.659574 (-4590 2010);
PAINT MONO (-4590 2010);
DISPLAY INVISIBLE (-4590 2010);
FORCEPROP 1 LAST VOLTAGE 1.1V
J 0
(-4645 2007);
DISPLAY 0.340426 (-4645 2007);
PAINT SKYBLUE (-4645 2007);
DISPLAY INVISIBLE (-4645 2007);
FORCEPROP 2 LAST CDS_LIB mstr_symbols
J 0
(-4600 2050);
PAINT ORANGE (-4600 2050);
DISPLAY INVISIBLE (-4600 2050);
FORCEPROP 1 LAST BODY_TYPE PLUMBING
J 0
(-4645 2007);
DISPLAY 0.340426 (-4645 2007);
PAINT GREEN (-4645 2007);
DISPLAY INVISIBLE (-4645 2007);
FORCEPROP 1 LAST PATH I66
J 0
(-4550 2075);
DISPLAY 0.872340 (-4550 2075);
PAINT AQUA (-4550 2075);
DISPLAY INVISIBLE (-4550 2075);
FORCEPROP 1 LAST HDL_POWER PVCCIO_CPU0
J 1
(-4600 2100);
DISPLAY 0.872340 (-4600 2100);
PAINT GREEN (-4600 2100);
DISPLAY INVISIBLE (-4600 2100);
FORCEADD RES..1
(-3725 1275);
FORCEPROP 1 LAST LOCATION R7D28
J 0
(-3775 1325);
DISPLAY 0.617021 (-3775 1325);
PAINT AQUA (-3775 1325);
FORCEPROP 1 LAST PART_NUMBER G21497-005
J 0
(-4100 1300);
DISPLAY 0.617021 (-4100 1300);
PAINT BLUE (-4100 1300);
FORCEPROP 1 LAST VALUE 0.0
J 2
(-3825 1225);
DISPLAY 0.617021 (-3825 1225);
PAINT SKYBLUE (-3825 1225);
FORCEPROP 1 LAST TOLERANCE 5%
J 0
(-3625 1175);
DISPLAY 0.617021 (-3625 1175);
PAINT SKYBLUE (-3625 1175);
FORCEPROP 1 LAST PACK_TYPE 0402
J 0
(-3850 1175);
DISPLAY 0.617021 (-3850 1175);
PAINT SKYBLUE (-3850 1175);
FORCEPROP 1 LAST MATERIAL CHIP
J 0
(-3750 1200);
DISPLAY 0.617021 (-3750 1200);
PAINT SKYBLUE (-3750 1200);
FORCEPROP 1 LAST WATTAGE 1/16W
J 2
(-3575 1225);
DISPLAY 0.617021 (-3575 1225);
PAINT SKYBLUE (-3575 1225);
FORCEPROP 1 LASTPIN (-3625 1275) $PN 2
J 0
(-3663 1287);
DISPLAY 0.617021 (-3663 1287);
PAINT ORANGE (-3663 1287);
FORCEPROP 1 LASTPIN (-3825 1275) $PN 1
J 0
(-3813 1287);
DISPLAY 0.617021 (-3813 1287);
PAINT ORANGE (-3813 1287);
FORCEPROP 2 LAST BOM_COST PROC_SIDEBAND
J 2
(-3725 1275);
PAINT MONO (-3725 1275);
DISPLAY INVISIBLE (-3725 1275);
FORCEPROP 2 LAST CDS_LIB mstr_discrete
J 0
(-3725 1275);
PAINT ORANGE (-3725 1275);
DISPLAY INVISIBLE (-3725 1275);
FORCEPROP 2 LAST SEC_TYPE 0402
J 0
(-3775 1475);
DISPLAY 1.021277 (-3775 1475);
PAINT ORANGE (-3775 1475);
DISPLAY INVISIBLE (-3775 1475);
FORCEPROP 2 LAST SEC 1
J 0
(-3775 1475);
DISPLAY 0.680851 (-3775 1475);
PAINT MONO (-3775 1475);
DISPLAY INVISIBLE (-3775 1475);
FORCEPROP 2 LAST CDS_LOCATION R7D28
J 0
(-3775 1325);
DISPLAY 0.617021 (-3775 1325);
PAINT AQUA (-3775 1325);
DISPLAY INVISIBLE (-3775 1325);
FORCEPROP 1 LAST PATH I67
J 0
(-3775 1425);
DISPLAY 0.978723 (-3775 1425);
PAINT WHITE (-3775 1425);
DISPLAY INVISIBLE (-3775 1425);
FORCEPROP 2 LAST ROOM PROC_SIDEBAND
J 0
(-3800 1200);
DISPLAY 0.617021 (-3800 1200);
PAINT ORANGE (-3800 1200);
DISPLAY INVISIBLE (-3800 1200);
FORCEADD RES..1
(-3775 1550);
FORCEPROP 1 LAST LOCATION R7D27
J 0
(-3825 1600);
DISPLAY 0.617021 (-3825 1600);
PAINT AQUA (-3825 1600);
FORCEPROP 1 LAST PART_NUMBER G21497-005
J 0
(-3900 1400);
DISPLAY 0.617021 (-3900 1400);
PAINT BLUE (-3900 1400);
FORCEPROP 1 LAST VALUE 0.0
J 2
(-3875 1500);
DISPLAY 0.617021 (-3875 1500);
PAINT SKYBLUE (-3875 1500);
FORCEPROP 1 LAST TOLERANCE 5%
J 0
(-3675 1450);
DISPLAY 0.617021 (-3675 1450);
PAINT SKYBLUE (-3675 1450);
FORCEPROP 1 LAST PACK_TYPE 0402
J 0
(-3900 1450);
DISPLAY 0.617021 (-3900 1450);
PAINT SKYBLUE (-3900 1450);
FORCEPROP 1 LAST MATERIAL CHIP
J 0
(-4050 1450);
DISPLAY 0.617021 (-4050 1450);
PAINT SKYBLUE (-4050 1450);
FORCEPROP 1 LAST WATTAGE 1/16W
J 2
(-3625 1500);
DISPLAY 0.617021 (-3625 1500);
PAINT SKYBLUE (-3625 1500);
FORCEPROP 1 LASTPIN (-3675 1550) $PN 2
J 0
(-3713 1562);
DISPLAY 0.617021 (-3713 1562);
PAINT ORANGE (-3713 1562);
FORCEPROP 1 LASTPIN (-3875 1550) $PN 1
J 0
(-3863 1562);
DISPLAY 0.617021 (-3863 1562);
PAINT ORANGE (-3863 1562);
FORCEPROP 2 LAST CDS_LIB mstr_discrete
J 0
(-3775 1550);
PAINT ORANGE (-3775 1550);
DISPLAY INVISIBLE (-3775 1550);
FORCEPROP 2 LAST SEC_TYPE 0402
J 0
(-3825 1750);
DISPLAY 1.021277 (-3825 1750);
PAINT ORANGE (-3825 1750);
DISPLAY INVISIBLE (-3825 1750);
FORCEPROP 2 LAST BOM_COST PROC_SIDEBAND
J 2
(-3775 1550);
PAINT MONO (-3775 1550);
DISPLAY INVISIBLE (-3775 1550);
FORCEPROP 2 LAST SEC 1
J 0
(-3825 1750);
DISPLAY 0.680851 (-3825 1750);
PAINT MONO (-3825 1750);
DISPLAY INVISIBLE (-3825 1750);
FORCEPROP 2 LAST CDS_LOCATION R7D27
J 0
(-3825 1600);
DISPLAY 0.617021 (-3825 1600);
PAINT AQUA (-3825 1600);
DISPLAY INVISIBLE (-3825 1600);
FORCEPROP 1 LAST PATH I68
J 0
(-3825 1700);
DISPLAY 0.978723 (-3825 1700);
PAINT WHITE (-3825 1700);
DISPLAY INVISIBLE (-3825 1700);
FORCEPROP 2 LAST ROOM PROC_SIDEBAND
J 0
(-3850 1475);
DISPLAY 0.617021 (-3850 1475);
PAINT ORANGE (-3850 1475);
DISPLAY INVISIBLE (-3850 1475);
FORCEADD OFFPAGE..5
R 2
(1075 1250);
FORCEPROP 2 LAST $XR0 147 
J 0
(1264 1250);
DISPLAY 0.638298 (1264 1250);
PAINT MONO (1264 1250);
FORCEPROP 2 LAST $XR1 120 
J 0
(1384 1250);
DISPLAY 0.638298 (1384 1250);
PAINT MONO (1384 1250);
FORCEPROP 2 LAST $XR2 190 
J 0
(1504 1250);
DISPLAY 0.638298 (1504 1250);
PAINT MONO (1504 1250);
FORCEPROP 2 LAST CDS_LIB mstr_standard
J 0
(1075 1250);
PAINT ORANGE (1075 1250);
DISPLAY INVISIBLE (1075 1250);
FORCEPROP 1 LAST OFFPAGE TRUE
J 2
(750 1125);
PAINT GREEN (750 1125);
DISPLAY INVISIBLE (750 1125);
FORCEPROP 1 LAST COMMENT_BODY TRUE
J 2
(975 1175);
DISPLAY 1.170213 (975 1175);
PAINT GREEN (975 1175);
DISPLAY INVISIBLE (975 1175);
FORCEPROP 2 LAST PATH I69
J 0
(1275 1300);
DISPLAY 1.021277 (1275 1300);
PAINT ORANGE (1275 1300);
DISPLAY INVISIBLE (1275 1300);
FORCEADD RES..1
(-100 1250);
FORCEPROP 1 LAST LOCATION R7D25
J 0
(-150 1300);
DISPLAY 0.617021 (-150 1300);
PAINT AQUA (-150 1300);
FORCEPROP 1 LAST PART_NUMBER G21796-074
J 0
(-25 1150);
DISPLAY 0.617021 (-25 1150);
PAINT BLUE (-25 1150);
FORCEPROP 1 LAST VALUE 33.2
J 2
(-125 1200);
DISPLAY 0.617021 (-125 1200);
PAINT SKYBLUE (-125 1200);
FORCEPROP 1 LAST TOLERANCE 1%
J 0
(-100 1200);
DISPLAY 0.617021 (-100 1200);
PAINT SKYBLUE (-100 1200);
FORCEPROP 1 LAST PACK_TYPE 0402
J 0
(0 1200);
DISPLAY 0.617021 (0 1200);
PAINT SKYBLUE (0 1200);
FORCEPROP 1 LAST MATERIAL CHIP
J 0
(-175 1150);
DISPLAY 0.617021 (-175 1150);
PAINT SKYBLUE (-175 1150);
FORCEPROP 1 LAST WATTAGE 1/16W
J 2
(-200 1150);
DISPLAY 0.617021 (-200 1150);
PAINT SKYBLUE (-200 1150);
FORCEPROP 1 LASTPIN (0 1250) $PN 2
J 0
(-38 1262);
DISPLAY 0.617021 (-38 1262);
PAINT ORANGE (-38 1262);
FORCEPROP 1 LASTPIN (-200 1250) $PN 1
J 0
(-188 1262);
DISPLAY 0.617021 (-188 1262);
PAINT ORANGE (-188 1262);
FORCEPROP 2 LAST SEC_TYPE 0402
J 0
(-150 1450);
DISPLAY 1.021277 (-150 1450);
PAINT ORANGE (-150 1450);
DISPLAY INVISIBLE (-150 1450);
FORCEPROP 2 LAST BOM_COST PROC_SIDEBAND
J 2
(-100 1250);
PAINT MONO (-100 1250);
DISPLAY INVISIBLE (-100 1250);
FORCEPROP 2 LAST CDS_LIB mstr_discrete
J 0
(-100 1250);
PAINT ORANGE (-100 1250);
DISPLAY INVISIBLE (-100 1250);
FORCEPROP 2 LAST SEC 1
J 0
(-150 1450);
DISPLAY 0.680851 (-150 1450);
PAINT MONO (-150 1450);
DISPLAY INVISIBLE (-150 1450);
FORCEPROP 2 LAST CDS_LOCATION R7D25
J 0
(-150 1300);
DISPLAY 0.617021 (-150 1300);
PAINT AQUA (-150 1300);
DISPLAY INVISIBLE (-150 1300);
FORCEPROP 1 LAST PATH I70
J 0
(-150 1400);
DISPLAY 0.978723 (-150 1400);
PAINT WHITE (-150 1400);
DISPLAY INVISIBLE (-150 1400);
FORCEPROP 2 LAST ROOM PROC_SIDEBAND
J 0
(-175 1175);
DISPLAY 0.617021 (-175 1175);
PAINT ORANGE (-175 1175);
DISPLAY INVISIBLE (-175 1175);
FORCEADD RES..2
(-2925 3900);
FORCEPROP 1 LAST LOCATION R3R2
J 0
(-2880 4025);
DISPLAY 0.617021 (-2880 4025);
PAINT AQUA (-2880 4025);
FORCEPROP 1 LAST PART_NUMBER G21796-026
J 0
(-2885 3775);
DISPLAY 0.617021 (-2885 3775);
PAINT BLUE (-2885 3775);
FORCEPROP 1 LAST VALUE 1.00K
J 0
(-2880 3975);
DISPLAY 0.617021 (-2880 3975);
PAINT SKYBLUE (-2880 3975);
FORCEPROP 1 LAST TOLERANCE 1%
J 0
(-2880 3925);
DISPLAY 0.617021 (-2880 3925);
PAINT SKYBLUE (-2880 3925);
FORCEPROP 1 LAST PACK_TYPE 0402
J 0
(-2885 3725);
DISPLAY 0.617021 (-2885 3725);
PAINT SKYBLUE (-2885 3725);
FORCEPROP 1 LAST MATERIAL CHIP
J 0
(-2885 3825);
DISPLAY 0.617021 (-2885 3825);
PAINT SKYBLUE (-2885 3825);
FORCEPROP 1 LAST WATTAGE 1/16W
J 0
(-2885 3875);
DISPLAY 0.617021 (-2885 3875);
PAINT SKYBLUE (-2885 3875);
FORCEPROP 1 LASTPIN (-2925 3800) $PN 2
J 0
(-2920 3810);
DISPLAY 0.617021 (-2920 3810);
PAINT ORANGE (-2920 3810);
FORCEPROP 1 LASTPIN (-2925 4000) $PN 1
J 0
(-2920 3962);
DISPLAY 0.617021 (-2920 3962);
PAINT ORANGE (-2920 3962);
FORCEPROP 2 LAST CDS_LIB mstr_discrete
J 0
(-2925 3900);
PAINT MONO (-2925 3900);
DISPLAY INVISIBLE (-2925 3900);
FORCEPROP 2 LAST SEC_TYPE 0402
J 0
(-2875 4125);
DISPLAY 1.021277 (-2875 4125);
PAINT ORANGE (-2875 4125);
DISPLAY INVISIBLE (-2875 4125);
FORCEPROP 2 LAST SEC 1
J 0
(-2875 4125);
DISPLAY 0.680851 (-2875 4125);
PAINT MONO (-2875 4125);
DISPLAY INVISIBLE (-2875 4125);
FORCEPROP 2 LAST CDS_LOCATION R3R2
J 0
(-2880 4025);
DISPLAY 0.617021 (-2880 4025);
PAINT AQUA (-2880 4025);
DISPLAY INVISIBLE (-2880 4025);
FORCEPROP 1 LAST PATH I75
J 0
(-2875 4075);
DISPLAY 0.978723 (-2875 4075);
PAINT WHITE (-2875 4075);
DISPLAY INVISIBLE (-2875 4075);
FORCEPROP 0 LAST ROOM PROC_SIDEBAND
J 0
(-2875 4125);
DISPLAY 1.021277 (-2875 4125);
PAINT ORANGE (-2875 4125);
DISPLAY INVISIBLE (-2875 4125);
FORCEADD GND..1
(-2925 3650);
FORCEPROP 3 LASTPIN (-2925 3700) SIG_NAME GND\g
J 0
(-2915 3710);
DISPLAY 0.659574 (-2915 3710);
PAINT MONO (-2915 3710);
DISPLAY INVISIBLE (-2915 3710);
FORCEPROP 1 LAST VOLTAGE 0
J 0
(-2925 3650);
PAINT SKYBLUE (-2925 3650);
DISPLAY INVISIBLE (-2925 3650);
FORCEPROP 1 LAST SIZE 1B
J 0
(-2850 3600);
DISPLAY 1.212766 (-2850 3600);
PAINT GREEN (-2850 3600);
DISPLAY INVISIBLE (-2850 3600);
FORCEPROP 2 LAST CDS_LIB mstr_symbols
J 0
(-2925 3650);
PAINT MONO (-2925 3650);
DISPLAY INVISIBLE (-2925 3650);
FORCEPROP 1 LAST BODY_TYPE PLUMBING
J 0
(-2970 3607);
DISPLAY 0.340426 (-2970 3607);
PAINT GREEN (-2970 3607);
DISPLAY INVISIBLE (-2970 3607);
FORCEPROP 1 LAST PATH I76
J 0
(-2850 3650);
DISPLAY 0.872340 (-2850 3650);
PAINT AQUA (-2850 3650);
DISPLAY INVISIBLE (-2850 3650);
FORCEPROP 1 LAST HDL_POWER GND
J 0
(-2925 3800);
DISPLAY 1.212766 (-2925 3800);
PAINT GREEN (-2925 3800);
DISPLAY INVISIBLE (-2925 3800);
FORCEADD CAP..1
(-900 2525);
FORCEPROP 1 LAST LOCATION C7D4
J 0
(-850 2625);
DISPLAY 0.617021 (-850 2625);
PAINT AQUA (-850 2625);
FORCEPROP 1 LAST PART_NUMBER D97712-011
J 0
(-850 2375);
DISPLAY 0.617021 (-850 2375);
PAINT BLUE (-850 2375);
FORCEPROP 1 LAST VALUE 1.0UF
J 0
(-850 2575);
DISPLAY 0.617021 (-850 2575);
PAINT SKYBLUE (-850 2575);
FORCEPROP 1 LAST TOLERANCE 10%
J 0
(-850 2475);
DISPLAY 0.617021 (-850 2475);
PAINT SKYBLUE (-850 2475);
FORCEPROP 1 LAST PACK_TYPE 0402
J 0
(-850 2325);
DISPLAY 0.617021 (-850 2325);
PAINT SKYBLUE (-850 2325);
FORCEPROP 1 LAST VOLTAGE 16V
J 0
(-850 2525);
DISPLAY 0.617021 (-850 2525);
PAINT SKYBLUE (-850 2525);
FORCEPROP 1 LAST MATERIAL X6S
J 0
(-850 2425);
DISPLAY 0.617021 (-850 2425);
PAINT SKYBLUE (-850 2425);
FORCEPROP 1 LASTPIN (-900 2425) $PN 2
J 0
(-890 2405);
DISPLAY 0.617021 (-890 2405);
PAINT ORANGE (-890 2405);
FORCEPROP 1 LASTPIN (-900 2625) $PN 1
J 0
(-890 2605);
DISPLAY 0.617021 (-890 2605);
PAINT ORANGE (-890 2605);
FORCEPROP 2 LAST CDS_LIB mstr_discrete
J 0
(-900 2525);
PAINT ORANGE (-900 2525);
DISPLAY INVISIBLE (-900 2525);
FORCEPROP 2 LAST SEC_TYPE 0402
J 0
(-850 2725);
DISPLAY 1.021277 (-850 2725);
PAINT ORANGE (-850 2725);
DISPLAY INVISIBLE (-850 2725);
FORCEPROP 0 LAST BOM_COST PROC
J 0
(-850 2725);
DISPLAY 1.021277 (-850 2725);
PAINT ORANGE (-850 2725);
DISPLAY INVISIBLE (-850 2725);
FORCEPROP 2 LAST SEC 1
J 0
(-850 2725);
DISPLAY 0.680851 (-850 2725);
PAINT MONO (-850 2725);
DISPLAY INVISIBLE (-850 2725);
FORCEPROP 2 LAST CDS_LOCATION C7D4
J 0
(-850 2625);
DISPLAY 0.617021 (-850 2625);
PAINT AQUA (-850 2625);
DISPLAY INVISIBLE (-850 2625);
FORCEPROP 1 LAST PATH I79
J 0
(-850 2675);
DISPLAY 0.978723 (-850 2675);
PAINT WHITE (-850 2675);
DISPLAY INVISIBLE (-850 2675);
FORCEPROP 0 LAST ROOM PROC_SIDEBAND
J 0
(-850 2725);
DISPLAY 1.021277 (-850 2725);
PAINT ORANGE (-850 2725);
DISPLAY INVISIBLE (-850 2725);
FORCEADD GND..1
(-900 2350);
FORCEPROP 3 LASTPIN (-900 2400) SIG_NAME GND\g
J 0
(-890 2410);
DISPLAY 0.659574 (-890 2410);
PAINT MONO (-890 2410);
DISPLAY INVISIBLE (-890 2410);
FORCEPROP 1 LAST VOLTAGE 0
J 0
(-900 2350);
PAINT SKYBLUE (-900 2350);
DISPLAY INVISIBLE (-900 2350);
FORCEPROP 2 LAST CDS_LIB mstr_symbols
J 0
(-900 2350);
PAINT ORANGE (-900 2350);
DISPLAY INVISIBLE (-900 2350);
FORCEPROP 1 LAST SIZE 1B
J 0
(-825 2300);
DISPLAY 1.212766 (-825 2300);
PAINT GREEN (-825 2300);
DISPLAY INVISIBLE (-825 2300);
FORCEPROP 1 LAST BODY_TYPE PLUMBING
J 0
(-945 2307);
DISPLAY 0.340426 (-945 2307);
PAINT GREEN (-945 2307);
DISPLAY INVISIBLE (-945 2307);
FORCEPROP 1 LAST PATH I80
J 0
(-825 2350);
DISPLAY 0.872340 (-825 2350);
PAINT AQUA (-825 2350);
DISPLAY INVISIBLE (-825 2350);
FORCEPROP 1 LAST HDL_POWER GND
J 0
(-900 2500);
DISPLAY 1.212766 (-900 2500);
PAINT GREEN (-900 2500);
DISPLAY INVISIBLE (-900 2500);
FORCEADD PVCCIO_CPU0..1
(-2850 2700);
FORCEPROP 3 LASTPIN (-2850 2650) SIG_NAME PVCCIO_CPU0\g
J 0
(-2840 2660);
DISPLAY 0.659574 (-2840 2660);
PAINT MONO (-2840 2660);
DISPLAY INVISIBLE (-2840 2660);
FORCEPROP 1 LAST VOLTAGE 1.1V
J 0
(-2895 2657);
DISPLAY 0.340426 (-2895 2657);
PAINT SKYBLUE (-2895 2657);
DISPLAY INVISIBLE (-2895 2657);
FORCEPROP 2 LAST CDS_LIB mstr_symbols
J 0
(-2850 2700);
PAINT ORANGE (-2850 2700);
DISPLAY INVISIBLE (-2850 2700);
FORCEPROP 1 LAST BODY_TYPE PLUMBING
J 0
(-2895 2657);
DISPLAY 0.340426 (-2895 2657);
PAINT GREEN (-2895 2657);
DISPLAY INVISIBLE (-2895 2657);
FORCEPROP 1 LAST PATH I82
J 0
(-2800 2725);
DISPLAY 0.872340 (-2800 2725);
PAINT AQUA (-2800 2725);
DISPLAY INVISIBLE (-2800 2725);
FORCEPROP 1 LAST HDL_POWER PVCCIO_CPU0
J 1
(-2850 2750);
DISPLAY 0.872340 (-2850 2750);
PAINT GREEN (-2850 2750);
DISPLAY INVISIBLE (-2850 2750);
FORCEADD CAP..1
(-1025 4725);
FORCEPROP 1 LAST LOCATION C3P50
J 0
(-975 4825);
DISPLAY 0.617021 (-975 4825);
PAINT AQUA (-975 4825);
FORCEPROP 1 LAST PART_NUMBER D97712-011
J 0
(-975 4575);
DISPLAY 0.617021 (-975 4575);
PAINT BLUE (-975 4575);
FORCEPROP 1 LAST VALUE 1.0UF
J 0
(-975 4775);
DISPLAY 0.617021 (-975 4775);
PAINT SKYBLUE (-975 4775);
FORCEPROP 1 LAST TOLERANCE 10%
J 0
(-975 4675);
DISPLAY 0.617021 (-975 4675);
PAINT SKYBLUE (-975 4675);
FORCEPROP 1 LAST PACK_TYPE 0402
J 0
(-975 4525);
DISPLAY 0.617021 (-975 4525);
PAINT SKYBLUE (-975 4525);
FORCEPROP 1 LAST VOLTAGE 16V
J 0
(-975 4725);
DISPLAY 0.617021 (-975 4725);
PAINT SKYBLUE (-975 4725);
FORCEPROP 1 LAST MATERIAL X6S
J 0
(-975 4625);
DISPLAY 0.617021 (-975 4625);
PAINT SKYBLUE (-975 4625);
FORCEPROP 1 LASTPIN (-1025 4625) $PN 2
J 0
(-1015 4605);
DISPLAY 0.617021 (-1015 4605);
PAINT ORANGE (-1015 4605);
FORCEPROP 1 LASTPIN (-1025 4825) $PN 1
J 0
(-1015 4805);
DISPLAY 0.617021 (-1015 4805);
PAINT ORANGE (-1015 4805);
FORCEPROP 2 LAST SEC_TYPE 0402
J 0
(-975 4925);
DISPLAY 1.021277 (-975 4925);
PAINT ORANGE (-975 4925);
DISPLAY INVISIBLE (-975 4925);
FORCEPROP 2 LAST CDS_LIB mstr_discrete
J 0
(-1025 4725);
PAINT ORANGE (-1025 4725);
DISPLAY INVISIBLE (-1025 4725);
FORCEPROP 0 LAST BOM_COST PROC
J 0
(-975 4925);
DISPLAY 1.021277 (-975 4925);
PAINT ORANGE (-975 4925);
DISPLAY INVISIBLE (-975 4925);
FORCEPROP 2 LAST SEC 1
J 0
(-975 4925);
DISPLAY 0.680851 (-975 4925);
PAINT MONO (-975 4925);
DISPLAY INVISIBLE (-975 4925);
FORCEPROP 2 LAST CDS_LOCATION C3P50
J 0
(-975 4825);
DISPLAY 0.617021 (-975 4825);
PAINT AQUA (-975 4825);
DISPLAY INVISIBLE (-975 4825);
FORCEPROP 1 LAST PATH I84
J 0
(-975 4875);
DISPLAY 0.978723 (-975 4875);
PAINT WHITE (-975 4875);
DISPLAY INVISIBLE (-975 4875);
FORCEPROP 0 LAST ROOM PROC_SIDEBAND
J 0
(-975 4925);
DISPLAY 1.021277 (-975 4925);
PAINT ORANGE (-975 4925);
DISPLAY INVISIBLE (-975 4925);
FORCEADD GND..1
(-1025 4550);
FORCEPROP 3 LASTPIN (-1025 4600) SIG_NAME GND\g
J 0
(-1015 4610);
DISPLAY 0.659574 (-1015 4610);
PAINT MONO (-1015 4610);
DISPLAY INVISIBLE (-1015 4610);
FORCEPROP 1 LAST VOLTAGE 0
J 0
(-1025 4550);
PAINT SKYBLUE (-1025 4550);
DISPLAY INVISIBLE (-1025 4550);
FORCEPROP 1 LAST SIZE 1B
J 0
(-950 4500);
DISPLAY 1.212766 (-950 4500);
PAINT GREEN (-950 4500);
DISPLAY INVISIBLE (-950 4500);
FORCEPROP 2 LAST CDS_LIB mstr_symbols
J 0
(-1025 4550);
PAINT ORANGE (-1025 4550);
DISPLAY INVISIBLE (-1025 4550);
FORCEPROP 1 LAST BODY_TYPE PLUMBING
J 0
(-1070 4507);
DISPLAY 0.340426 (-1070 4507);
PAINT GREEN (-1070 4507);
DISPLAY INVISIBLE (-1070 4507);
FORCEPROP 1 LAST PATH I85
J 0
(-950 4550);
DISPLAY 0.872340 (-950 4550);
PAINT AQUA (-950 4550);
DISPLAY INVISIBLE (-950 4550);
FORCEPROP 1 LAST HDL_POWER GND
J 0
(-1025 4700);
DISPLAY 1.212766 (-1025 4700);
PAINT GREEN (-1025 4700);
DISPLAY INVISIBLE (-1025 4700);
FORCEADD OFFPAGE..2
(1050 4000);
FORCEPROP 2 LAST $XR0 144 
J 0
(1239 4000);
DISPLAY 0.638298 (1239 4000);
PAINT MONO (1239 4000);
FORCEPROP 2 LAST $XR1 190 
J 0
(1359 4000);
DISPLAY 0.638298 (1359 4000);
PAINT MONO (1359 4000);
FORCEPROP 2 LAST CDS_LIB mstr_standard
J 0
(1050 4000);
PAINT MONO (1050 4000);
DISPLAY INVISIBLE (1050 4000);
FORCEPROP 1 LAST OFFPAGE TRUE
J 0
(1375 3875);
PAINT GREEN (1375 3875);
DISPLAY INVISIBLE (1375 3875);
FORCEPROP 1 LAST COMMENT_BODY TRUE
J 0
(1005 3905);
DISPLAY 1.085106 (1005 3905);
PAINT GREEN (1005 3905);
DISPLAY INVISIBLE (1005 3905);
FORCEPROP 2 LAST PATH I88
J 0
(1375 4050);
DISPLAY 1.021277 (1375 4050);
PAINT ORANGE (1375 4050);
DISPLAY INVISIBLE (1375 4050);
FORCEADD OFFPAGE..5
R 2
(1075 1800);
FORCEPROP 2 LAST $XR0 120 
J 0
(1264 1800);
DISPLAY 0.638298 (1264 1800);
PAINT MONO (1264 1800);
FORCEPROP 2 LAST $XR1 144 
J 0
(1384 1800);
DISPLAY 0.638298 (1384 1800);
PAINT MONO (1384 1800);
FORCEPROP 2 LAST CDS_LIB mstr_standard
J 0
(1075 1800);
PAINT ORANGE (1075 1800);
DISPLAY INVISIBLE (1075 1800);
FORCEPROP 1 LAST OFFPAGE TRUE
J 2
(750 1675);
PAINT GREEN (750 1675);
DISPLAY INVISIBLE (750 1675);
FORCEPROP 1 LAST COMMENT_BODY TRUE
J 2
(975 1725);
DISPLAY 1.170213 (975 1725);
PAINT GREEN (975 1725);
DISPLAY INVISIBLE (975 1725);
FORCEPROP 2 LAST PATH I89
J 0
(1400 1850);
DISPLAY 1.021277 (1400 1850);
PAINT ORANGE (1400 1850);
DISPLAY INVISIBLE (1400 1850);
FORCEADD RES..2
(-2900 4525);
FORCEPROP 1 LAST LOCATION R3P41
J 0
(-2855 4650);
DISPLAY 0.617021 (-2855 4650);
PAINT AQUA (-2855 4650);
FORCEPROP 1 LAST PART_NUMBER G21796-267
J 0
(-2860 4400);
DISPLAY 0.617021 (-2860 4400);
PAINT BLUE (-2860 4400);
FORCEPROP 1 LAST VALUE 75
J 0
(-2855 4600);
DISPLAY 0.617021 (-2855 4600);
PAINT SKYBLUE (-2855 4600);
FORCEPROP 1 LAST TOLERANCE 1.0%
J 0
(-2855 4550);
DISPLAY 0.617021 (-2855 4550);
PAINT SKYBLUE (-2855 4550);
FORCEPROP 1 LAST PACK_TYPE 0402
J 0
(-2860 4350);
DISPLAY 0.617021 (-2860 4350);
PAINT SKYBLUE (-2860 4350);
FORCEPROP 1 LAST MATERIAL CHIP
J 0
(-2860 4450);
DISPLAY 0.617021 (-2860 4450);
PAINT SKYBLUE (-2860 4450);
FORCEPROP 1 LAST WATTAGE 1/16W
J 0
(-2860 4500);
DISPLAY 0.617021 (-2860 4500);
PAINT SKYBLUE (-2860 4500);
FORCEPROP 1 LASTPIN (-2900 4425) $PN 2
J 0
(-2895 4435);
DISPLAY 0.617021 (-2895 4435);
PAINT ORANGE (-2895 4435);
FORCEPROP 1 LASTPIN (-2900 4625) $PN 1
J 0
(-2895 4587);
DISPLAY 0.617021 (-2895 4587);
PAINT ORANGE (-2895 4587);
FORCEPROP 2 LAST CDS_LIB mstr_discrete
J 0
(-2900 4525);
PAINT ORANGE (-2900 4525);
DISPLAY INVISIBLE (-2900 4525);
FORCEPROP 2 LAST BOM_COST PROC_SIDEBAND
J 0
(-2900 4525);
PAINT MONO (-2900 4525);
DISPLAY INVISIBLE (-2900 4525);
FORCEPROP 2 LAST SEC_TYPE 0402
J 0
(-2850 4750);
DISPLAY 1.021277 (-2850 4750);
PAINT ORANGE (-2850 4750);
DISPLAY INVISIBLE (-2850 4750);
FORCEPROP 2 LAST SEC 1
J 0
(-2850 4750);
DISPLAY 0.680851 (-2850 4750);
PAINT MONO (-2850 4750);
DISPLAY INVISIBLE (-2850 4750);
FORCEPROP 2 LAST CDS_LOCATION R3P41
J 0
(-2855 4650);
DISPLAY 0.617021 (-2855 4650);
PAINT AQUA (-2855 4650);
DISPLAY INVISIBLE (-2855 4650);
FORCEPROP 1 LAST PATH I9
J 0
(-2850 4700);
DISPLAY 0.978723 (-2850 4700);
PAINT WHITE (-2850 4700);
DISPLAY INVISIBLE (-2850 4700);
FORCEPROP 2 LAST ROOM PROC_SIDEBAND
J 0
(-2875 4300);
PAINT ORANGE (-2875 4300);
DISPLAY INVISIBLE (-2875 4300);
FORCEADD OFFPAGE..1
(-5200 2800);
FORCEPROP 2 LAST $XR0 21 
J 0
(-5421 2800);
DISPLAY 0.638298 (-5421 2800);
PAINT MONO (-5421 2800);
FORCEPROP 2 LAST CDS_LIB mstr_standard
J 0
(-5200 2800);
PAINT ORANGE (-5200 2800);
DISPLAY INVISIBLE (-5200 2800);
FORCEPROP 1 LAST OFFPAGE TRUE
J 0
(-4875 2675);
PAINT GREEN (-4875 2675);
DISPLAY INVISIBLE (-4875 2675);
FORCEPROP 1 LAST COMMENT_BODY TRUE
J 0
(-5075 2700);
DISPLAY 1.170213 (-5075 2700);
PAINT GREEN (-5075 2700);
DISPLAY INVISIBLE (-5075 2700);
FORCEPROP 2 LAST PATH I90
J 0
(-5400 2850);
DISPLAY 1.021277 (-5400 2850);
PAINT ORANGE (-5400 2850);
DISPLAY INVISIBLE (-5400 2850);
FORCEADD OFFPAGE..1
(-5200 2550);
FORCEPROP 2 LAST $XR0 55 
J 0
(-5421 2550);
DISPLAY 0.638298 (-5421 2550);
PAINT MONO (-5421 2550);
FORCEPROP 2 LAST CDS_LIB mstr_standard
J 0
(-5200 2550);
PAINT ORANGE (-5200 2550);
DISPLAY INVISIBLE (-5200 2550);
FORCEPROP 1 LAST OFFPAGE TRUE
J 0
(-4875 2425);
PAINT GREEN (-4875 2425);
DISPLAY INVISIBLE (-4875 2425);
FORCEPROP 1 LAST COMMENT_BODY TRUE
J 0
(-5075 2450);
DISPLAY 1.170213 (-5075 2450);
PAINT GREEN (-5075 2450);
DISPLAY INVISIBLE (-5075 2450);
FORCEPROP 2 LAST PATH I91
J 0
(-5400 2600);
DISPLAY 1.021277 (-5400 2600);
PAINT ORANGE (-5400 2600);
DISPLAY INVISIBLE (-5400 2600);
FORCEADD RES..1
(-4575 2550);
FORCEPROP 1 LAST LOCATION R2T44
J 0
(-4625 2600);
DISPLAY 0.617021 (-4625 2600);
PAINT AQUA (-4625 2600);
FORCEPROP 1 LAST PART_NUMBER G21497-005
J 0
(-4725 2400);
DISPLAY 0.617021 (-4725 2400);
PAINT BLUE (-4725 2400);
FORCEPROP 1 LAST VALUE 0.0
J 2
(-4700 2500);
DISPLAY 0.617021 (-4700 2500);
PAINT SKYBLUE (-4700 2500);
FORCEPROP 1 LAST TOLERANCE 5%
J 0
(-4675 2500);
DISPLAY 0.617021 (-4675 2500);
PAINT SKYBLUE (-4675 2500);
FORCEPROP 1 LAST PACK_TYPE 0402
J 0
(-4550 2450);
DISPLAY 0.617021 (-4550 2450);
PAINT SKYBLUE (-4550 2450);
FORCEPROP 1 LAST MATERIAL CHIP
J 0
(-4675 2450);
DISPLAY 0.617021 (-4675 2450);
PAINT SKYBLUE (-4675 2450);
FORCEPROP 1 LAST WATTAGE 1/16W
J 2
(-4475 2500);
DISPLAY 0.617021 (-4475 2500);
PAINT SKYBLUE (-4475 2500);
FORCEPROP 1 LASTPIN (-4475 2550) $PN 2
J 0
(-4513 2562);
DISPLAY 0.617021 (-4513 2562);
PAINT ORANGE (-4513 2562);
FORCEPROP 1 LASTPIN (-4675 2550) $PN 1
J 0
(-4663 2562);
DISPLAY 0.617021 (-4663 2562);
PAINT ORANGE (-4663 2562);
FORCEPROP 2 LAST BOM_COST PROC
J 2
(-4575 2550);
PAINT MONO (-4575 2550);
DISPLAY INVISIBLE (-4575 2550);
FORCEPROP 2 LAST CDS_LIB mstr_discrete
J 0
(-4575 2550);
PAINT ORANGE (-4575 2550);
DISPLAY INVISIBLE (-4575 2550);
FORCEPROP 2 LAST CDS_SEC 1
J 0
(-4625 2750);
DISPLAY 1.021277 (-4625 2750);
PAINT ORANGE (-4625 2750);
DISPLAY INVISIBLE (-4625 2750);
FORCEPROP 2 LAST $SEC 1
J 0
(-4625 2750);
DISPLAY 0.680851 (-4625 2750);
PAINT MONO (-4625 2750);
DISPLAY INVISIBLE (-4625 2750);
FORCEPROP 2 LAST CDS_LOCATION R2T44
J 0
(-4625 2600);
DISPLAY 0.617021 (-4625 2600);
PAINT AQUA (-4625 2600);
DISPLAY INVISIBLE (-4625 2600);
FORCEPROP 1 LAST PATH I92
J 0
(-4625 2700);
DISPLAY 0.978723 (-4625 2700);
PAINT WHITE (-4625 2700);
DISPLAY INVISIBLE (-4625 2700);
FORCEPROP 2 LAST ROOM PROC_SIDEBAND
J 0
(-4650 2475);
DISPLAY 0.617021 (-4650 2475);
PAINT ORANGE (-4650 2475);
DISPLAY INVISIBLE (-4650 2475);
FORCEADD RES..1
(-4600 2800);
FORCEPROP 1 LAST LOCATION R2T40
J 0
(-4650 2850);
DISPLAY 0.617021 (-4650 2850);
PAINT AQUA (-4650 2850);
FORCEPROP 1 LAST PART_NUMBER G21497-005
J 0
(-4725 2650);
DISPLAY 0.617021 (-4725 2650);
PAINT BLUE (-4725 2650);
FORCEPROP 1 LAST VALUE 0.0
J 2
(-4700 2750);
DISPLAY 0.617021 (-4700 2750);
PAINT SKYBLUE (-4700 2750);
FORCEPROP 1 LAST TOLERANCE 5%
J 0
(-4675 2750);
DISPLAY 0.617021 (-4675 2750);
PAINT SKYBLUE (-4675 2750);
FORCEPROP 1 LAST PACK_TYPE 0402
J 0
(-4550 2700);
DISPLAY 0.617021 (-4550 2700);
PAINT SKYBLUE (-4550 2700);
FORCEPROP 1 LAST MATERIAL CHIP
J 0
(-4675 2700);
DISPLAY 0.617021 (-4675 2700);
PAINT SKYBLUE (-4675 2700);
FORCEPROP 1 LAST WATTAGE 1/16W
J 2
(-4475 2750);
DISPLAY 0.617021 (-4475 2750);
PAINT SKYBLUE (-4475 2750);
FORCEPROP 1 LASTPIN (-4500 2800) $PN 2
J 0
(-4538 2812);
DISPLAY 0.617021 (-4538 2812);
PAINT ORANGE (-4538 2812);
FORCEPROP 1 LASTPIN (-4700 2800) $PN 1
J 0
(-4688 2812);
DISPLAY 0.617021 (-4688 2812);
PAINT ORANGE (-4688 2812);
FORCEPROP 2 LAST BOM_COST PROC
J 2
(-4600 2800);
PAINT MONO (-4600 2800);
DISPLAY INVISIBLE (-4600 2800);
FORCEPROP 2 LAST CDS_LIB mstr_discrete
J 0
(-4600 2800);
PAINT ORANGE (-4600 2800);
DISPLAY INVISIBLE (-4600 2800);
FORCEPROP 2 LAST CDS_SEC 1
J 0
(-4650 3000);
DISPLAY 1.021277 (-4650 3000);
PAINT ORANGE (-4650 3000);
DISPLAY INVISIBLE (-4650 3000);
FORCEPROP 2 LAST $SEC 1
J 0
(-4650 3000);
DISPLAY 0.680851 (-4650 3000);
PAINT MONO (-4650 3000);
DISPLAY INVISIBLE (-4650 3000);
FORCEPROP 2 LAST CDS_LOCATION R2T40
J 0
(-4650 2850);
DISPLAY 0.617021 (-4650 2850);
PAINT AQUA (-4650 2850);
DISPLAY INVISIBLE (-4650 2850);
FORCEPROP 1 LAST PATH I93
J 0
(-4650 2950);
DISPLAY 0.978723 (-4650 2950);
PAINT WHITE (-4650 2950);
DISPLAY INVISIBLE (-4650 2950);
FORCEPROP 2 LAST ROOM PROC_SIDEBAND
J 0
(-4675 2725);
DISPLAY 0.617021 (-4675 2725);
PAINT ORANGE (-4675 2725);
DISPLAY INVISIBLE (-4675 2725);
FORCEADD RES..2
(-4000 2950);
FORCEPROP 1 LAST LOCATION R2T37
J 0
(-3955 3075);
DISPLAY 0.617021 (-3955 3075);
PAINT AQUA (-3955 3075);
FORCEPROP 1 LAST PART_NUMBER G21796-004
J 0
(-3960 2825);
DISPLAY 0.617021 (-3960 2825);
PAINT BLUE (-3960 2825);
FORCEPROP 1 LAST VALUE 200.0
J 0
(-3955 3025);
DISPLAY 0.617021 (-3955 3025);
PAINT SKYBLUE (-3955 3025);
FORCEPROP 1 LAST TOLERANCE 1%
J 0
(-3955 2975);
DISPLAY 0.617021 (-3955 2975);
PAINT SKYBLUE (-3955 2975);
FORCEPROP 1 LAST PACK_TYPE 0402
J 0
(-3960 2775);
DISPLAY 0.617021 (-3960 2775);
PAINT SKYBLUE (-3960 2775);
FORCEPROP 1 LAST MATERIAL CHIP
J 0
(-3960 2875);
DISPLAY 0.617021 (-3960 2875);
PAINT SKYBLUE (-3960 2875);
FORCEPROP 1 LAST WATTAGE 1/16W
J 0
(-3960 2925);
DISPLAY 0.617021 (-3960 2925);
PAINT SKYBLUE (-3960 2925);
FORCEPROP 2 LAST CDS_LIB mstr_discrete
J 0
(-4000 2950);
PAINT ORANGE (-4000 2950);
DISPLAY INVISIBLE (-4000 2950);
FORCEPROP 2 LAST BOM_COST PROC
J 0
(-4000 2950);
PAINT MONO (-4000 2950);
DISPLAY INVISIBLE (-4000 2950);
FORCEPROP 2 LAST CDS_SEC 1
J 0
(-3950 3175);
DISPLAY 1.021277 (-3950 3175);
PAINT ORANGE (-3950 3175);
DISPLAY INVISIBLE (-3950 3175);
FORCEPROP 2 LAST $SEC 1
J 0
(-3950 3175);
DISPLAY 0.680851 (-3950 3175);
PAINT MONO (-3950 3175);
DISPLAY INVISIBLE (-3950 3175);
FORCEPROP 2 LAST CDS_LOCATION R2T37
J 0
(-3955 3075);
DISPLAY 0.617021 (-3955 3075);
PAINT AQUA (-3955 3075);
DISPLAY INVISIBLE (-3955 3075);
FORCEPROP 1 LAST PATH I94
J 0
(-3950 3125);
DISPLAY 0.978723 (-3950 3125);
PAINT WHITE (-3950 3125);
DISPLAY INVISIBLE (-3950 3125);
FORCEPROP 2 LAST ROOM PROC_SIDEBAND
J 0
(-3975 2725);
PAINT ORANGE (-3975 2725);
DISPLAY INVISIBLE (-3975 2725);
FORCEPROP 1 LASTPIN (-4000 2850) $PN 2
J 0
(-3995 2860);
DISPLAY 0.787234 (-3995 2860);
PAINT ORANGE (-3995 2860);
DISPLAY INVISIBLE (-3995 2860);
FORCEPROP 1 LASTPIN (-4000 3050) $PN 1
J 0
(-3995 3012);
DISPLAY 0.787234 (-3995 3012);
PAINT ORANGE (-3995 3012);
DISPLAY INVISIBLE (-3995 3012);
FORCEADD PVCCIO_CPU0..1
(-4000 3175);
FORCEPROP 3 LASTPIN (-4000 3125) SIG_NAME PVCCIO_CPU0\g
J 0
(-3990 3135);
DISPLAY 0.659574 (-3990 3135);
PAINT MONO (-3990 3135);
DISPLAY INVISIBLE (-3990 3135);
FORCEPROP 1 LAST VOLTAGE 1.1V
J 0
(-4045 3132);
DISPLAY 0.340426 (-4045 3132);
PAINT SKYBLUE (-4045 3132);
DISPLAY INVISIBLE (-4045 3132);
FORCEPROP 2 LAST CDS_LIB mstr_symbols
J 0
(-4000 3175);
PAINT ORANGE (-4000 3175);
DISPLAY INVISIBLE (-4000 3175);
FORCEPROP 1 LAST BODY_TYPE PLUMBING
J 0
(-4045 3132);
DISPLAY 0.340426 (-4045 3132);
PAINT GREEN (-4045 3132);
DISPLAY INVISIBLE (-4045 3132);
FORCEPROP 1 LAST PATH I95
J 0
(-3950 3200);
DISPLAY 0.872340 (-3950 3200);
PAINT AQUA (-3950 3200);
DISPLAY INVISIBLE (-3950 3200);
FORCEPROP 1 LAST HDL_POWER PVCCIO_CPU0
J 1
(-4000 3225);
DISPLAY 0.872340 (-4000 3225);
PAINT GREEN (-4000 3225);
DISPLAY INVISIBLE (-4000 3225);
FORCEADD RES..1
(-3675 2675);
FORCEPROP 1 LAST LOCATION R2T43
J 0
(-3725 2725);
DISPLAY 0.617021 (-3725 2725);
PAINT AQUA (-3725 2725);
FORCEPROP 1 LAST PART_NUMBER G21796-267
J 0
(-3725 2775);
DISPLAY 0.617021 (-3725 2775);
PAINT BLUE (-3725 2775);
FORCEPROP 1 LAST VALUE 75
J 2
(-3700 2575);
DISPLAY 0.617021 (-3700 2575);
PAINT SKYBLUE (-3700 2575);
FORCEPROP 1 LAST TOLERANCE 1.0%
J 0
(-3675 2575);
DISPLAY 0.617021 (-3675 2575);
PAINT SKYBLUE (-3675 2575);
FORCEPROP 1 LAST PACK_TYPE 0402
J 0
(-3750 2475);
DISPLAY 0.617021 (-3750 2475);
PAINT SKYBLUE (-3750 2475);
FORCEPROP 1 LAST MATERIAL CHIP
J 0
(-3675 2525);
DISPLAY 0.617021 (-3675 2525);
PAINT SKYBLUE (-3675 2525);
FORCEPROP 1 LAST WATTAGE 1/16W
J 2
(-3700 2525);
DISPLAY 0.617021 (-3700 2525);
PAINT SKYBLUE (-3700 2525);
FORCEPROP 1 LASTPIN (-3575 2675) $PN 2
J 0
(-3613 2687);
DISPLAY 0.617021 (-3613 2687);
PAINT ORANGE (-3613 2687);
FORCEPROP 1 LASTPIN (-3775 2675) $PN 1
J 0
(-3763 2687);
DISPLAY 0.617021 (-3763 2687);
PAINT ORANGE (-3763 2687);
FORCEPROP 2 LAST BOM_COST PROC
J 2
(-3675 2675);
PAINT MONO (-3675 2675);
DISPLAY INVISIBLE (-3675 2675);
FORCEPROP 2 LAST CDS_LIB mstr_discrete
J 0
(-3675 2675);
PAINT ORANGE (-3675 2675);
DISPLAY INVISIBLE (-3675 2675);
FORCEPROP 2 LAST CDS_SEC 1
J 0
(-3725 2875);
DISPLAY 1.021277 (-3725 2875);
PAINT ORANGE (-3725 2875);
DISPLAY INVISIBLE (-3725 2875);
FORCEPROP 2 LAST $SEC 1
J 0
(-3725 2875);
DISPLAY 0.680851 (-3725 2875);
PAINT MONO (-3725 2875);
DISPLAY INVISIBLE (-3725 2875);
FORCEPROP 2 LAST CDS_LOCATION R2T43
J 0
(-3725 2725);
DISPLAY 0.617021 (-3725 2725);
PAINT AQUA (-3725 2725);
DISPLAY INVISIBLE (-3725 2725);
FORCEPROP 1 LAST PATH I96
J 0
(-3725 2825);
DISPLAY 0.978723 (-3725 2825);
PAINT WHITE (-3725 2825);
DISPLAY INVISIBLE (-3725 2825);
FORCEPROP 2 LAST ROOM PROC_SIDEBAND
J 0
(-3750 2600);
DISPLAY 0.617021 (-3750 2600);
PAINT ORANGE (-3750 2600);
DISPLAY INVISIBLE (-3750 2600);
FORCEADD RES..1
(-3775 4350);
FORCEPROP 1 LAST LOCATION R3P59
J 0
(-3850 4400);
DISPLAY 0.617021 (-3850 4400);
PAINT AQUA (-3850 4400);
FORCEPROP 1 LAST PART_NUMBER G21497-005
J 0
(-3975 4250);
DISPLAY 0.617021 (-3975 4250);
PAINT BLUE (-3975 4250);
FORCEPROP 1 LAST VALUE 0.0
J 2
(-3900 4350);
DISPLAY 0.617021 (-3900 4350);
PAINT SKYBLUE (-3900 4350);
FORCEPROP 1 LAST TOLERANCE 5%
J 0
(-3750 4250);
DISPLAY 0.617021 (-3750 4250);
PAINT SKYBLUE (-3750 4250);
FORCEPROP 1 LAST PACK_TYPE 0402
J 0
(-3825 4300);
DISPLAY 0.617021 (-3825 4300);
PAINT SKYBLUE (-3825 4300);
FORCEPROP 1 LAST MATERIAL CHIP
J 0
(-3950 4300);
DISPLAY 0.617021 (-3950 4300);
PAINT SKYBLUE (-3950 4300);
FORCEPROP 1 LAST WATTAGE 1/16W
J 2
(-3600 4300);
DISPLAY 0.617021 (-3600 4300);
PAINT SKYBLUE (-3600 4300);
FORCEPROP 1 LASTPIN (-3675 4350) $PN 2
J 0
(-3713 4362);
DISPLAY 0.617021 (-3713 4362);
PAINT MONO (-3713 4362);
FORCEPROP 1 LASTPIN (-3875 4350) $PN 1
J 0
(-3863 4362);
DISPLAY 0.617021 (-3863 4362);
PAINT MONO (-3863 4362);
FORCEPROP 2 LAST CDS_LIB mstr_discrete
J 0
(-3775 4350);
PAINT ORANGE (-3775 4350);
DISPLAY INVISIBLE (-3775 4350);
FORCEPROP 2 LAST SEC_TYPE 0402
J 0
(-3825 4550);
DISPLAY 1.021277 (-3825 4550);
PAINT ORANGE (-3825 4550);
DISPLAY INVISIBLE (-3825 4550);
FORCEPROP 2 LAST BOM_COST PROC
J 2
(-3775 4350);
PAINT MONO (-3775 4350);
DISPLAY INVISIBLE (-3775 4350);
FORCEPROP 2 LAST SEC 1
J 0
(-3825 4550);
DISPLAY 0.680851 (-3825 4550);
PAINT MONO (-3825 4550);
DISPLAY INVISIBLE (-3825 4550);
FORCEPROP 1 LAST PATH I97
J 0
(-3825 4500);
DISPLAY 0.978723 (-3825 4500);
PAINT WHITE (-3825 4500);
DISPLAY INVISIBLE (-3825 4500);
FORCEPROP 2 LAST ROOM PROC_SIDEBAND
J 0
(-3850 4275);
DISPLAY 0.617021 (-3850 4275);
PAINT ORANGE (-3850 4275);
DISPLAY INVISIBLE (-3850 4275);
FORCEADD RES..1
(-3750 4100);
FORCEPROP 1 LAST LOCATION R3P58
J 0
(-3825 4150);
DISPLAY 0.617021 (-3825 4150);
PAINT AQUA (-3825 4150);
FORCEPROP 1 LAST PART_NUMBER G21497-005
J 0
(-3950 4000);
DISPLAY 0.617021 (-3950 4000);
PAINT BLUE (-3950 4000);
FORCEPROP 1 LAST VALUE 0.0
J 2
(-3875 4100);
DISPLAY 0.617021 (-3875 4100);
PAINT SKYBLUE (-3875 4100);
FORCEPROP 1 LAST TOLERANCE 5%
J 0
(-3725 4000);
DISPLAY 0.617021 (-3725 4000);
PAINT SKYBLUE (-3725 4000);
FORCEPROP 1 LAST PACK_TYPE 0402
J 0
(-3825 4050);
DISPLAY 0.617021 (-3825 4050);
PAINT SKYBLUE (-3825 4050);
FORCEPROP 1 LAST MATERIAL CHIP
J 0
(-3950 4050);
DISPLAY 0.617021 (-3950 4050);
PAINT SKYBLUE (-3950 4050);
FORCEPROP 1 LAST WATTAGE 1/16W
J 2
(-3600 4050);
DISPLAY 0.617021 (-3600 4050);
PAINT SKYBLUE (-3600 4050);
FORCEPROP 1 LASTPIN (-3650 4100) $PN 2
J 0
(-3688 4112);
DISPLAY 0.617021 (-3688 4112);
PAINT MONO (-3688 4112);
FORCEPROP 1 LASTPIN (-3850 4100) $PN 1
J 0
(-3838 4112);
DISPLAY 0.617021 (-3838 4112);
PAINT MONO (-3838 4112);
FORCEPROP 2 LAST BOM_COST PROC
J 0
(-3750 4100);
PAINT MONO (-3750 4100);
DISPLAY INVISIBLE (-3750 4100);
FORCEPROP 2 LAST SEC_TYPE 0402
J 0
(-3800 4300);
DISPLAY 1.021277 (-3800 4300);
PAINT ORANGE (-3800 4300);
DISPLAY INVISIBLE (-3800 4300);
FORCEPROP 2 LAST CDS_LIB mstr_discrete
J 0
(-3750 4100);
PAINT ORANGE (-3750 4100);
DISPLAY INVISIBLE (-3750 4100);
FORCEPROP 2 LAST SEC 1
J 0
(-3800 4300);
DISPLAY 0.680851 (-3800 4300);
PAINT MONO (-3800 4300);
DISPLAY INVISIBLE (-3800 4300);
FORCEPROP 1 LAST PATH I98
J 0
(-3800 4250);
DISPLAY 0.978723 (-3800 4250);
PAINT WHITE (-3800 4250);
DISPLAY INVISIBLE (-3800 4250);
FORCEPROP 2 LAST ROOM PROC_SIDEBAND
J 0
(-3825 4025);
DISPLAY 0.617021 (-3825 4025);
PAINT ORANGE (-3825 4025);
DISPLAY INVISIBLE (-3825 4025);
FORCEADD PVCCIO_CPU0..1
(-4450 4850);
FORCEPROP 3 LASTPIN (-4450 4800) SIG_NAME PVCCIO_CPU0\g
J 0
(-4440 4810);
DISPLAY 0.659574 (-4440 4810);
PAINT MONO (-4440 4810);
DISPLAY INVISIBLE (-4440 4810);
FORCEPROP 1 LAST VOLTAGE 1.1V
J 0
(-4495 4807);
DISPLAY 0.340426 (-4495 4807);
PAINT SKYBLUE (-4495 4807);
DISPLAY INVISIBLE (-4495 4807);
FORCEPROP 2 LAST CDS_LIB mstr_symbols
J 0
(-4450 4850);
PAINT ORANGE (-4450 4850);
DISPLAY INVISIBLE (-4450 4850);
FORCEPROP 1 LAST BODY_TYPE PLUMBING
J 0
(-4495 4807);
DISPLAY 0.340426 (-4495 4807);
PAINT GREEN (-4495 4807);
DISPLAY INVISIBLE (-4495 4807);
FORCEPROP 1 LAST PATH I99
J 0
(-4400 4875);
DISPLAY 0.872340 (-4400 4875);
PAINT AQUA (-4400 4875);
DISPLAY INVISIBLE (-4400 4875);
FORCEPROP 1 LAST HDL_POWER PVCCIO_CPU0
J 1
(-4450 4900);
DISPLAY 0.872340 (-4450 4900);
PAINT GREEN (-4450 4900);
DISPLAY INVISIBLE (-4450 4900);
FORCEADD CAD_NOTE..1
(-4750 2275);
FORCEPROP 0 LAST L1 PLACE PULLUP RESISTOR WITHIN 2.5 INCH OF CPU0
J 0
(-4900 2175);
DISPLAY 0.638298 (-4900 2175);
PAINT ORANGE (-4900 2175);
FORCEPROP 2 LAST CDS_LIB mstr_symbols
J 0
(-4750 2275);
PAINT ORANGE (-4750 2275);
DISPLAY INVISIBLE (-4750 2275);
FORCEPROP 2 LAST BOM_COST SM_CONTROLLER
J 0
(-4900 2225);
PAINT WHITE (-4900 2225);
DISPLAY INVISIBLE (-4900 2225);
FORCEPROP 1 LAST COMMENT_BODY TRUE
J 0
(-4725 2375);
DISPLAY 1.319149 (-4725 2375);
PAINT WHITE (-4725 2375);
DISPLAY INVISIBLE (-4725 2375);
FORCEPROP 2 LAST ROOM PROC_SIDEBAND
J 0
(-4900 2225);
PAINT WHITE (-4900 2225);
DISPLAY INVISIBLE (-4900 2225);
FORCEADD DESIGN_NOTE..1
(-1950 1500);
PAINT PURPLE (-1950 1500);
FORCEPROP 0 LAST L1 THE GTL2014 IS BEING USED AS GTL TO LVTTL CONVERTER, SO
J 0
(-2150 1375);
DISPLAY 0.808511 (-2150 1375);
PAINT VIOLET (-2150 1375);
FORCEPROP 0 LAST L3 VREF IS SET AT 2/3 OF VCCIO
J 0
(-2150 1275);
DISPLAY 0.808511 (-2150 1275);
PAINT VIOLET (-2150 1275);
FORCEPROP 0 LAST L2 THE PINS 'BX' ARE INPUTS & 'AX' OUTPUTS ARE PUSH-PULL.
J 0
(-2150 1325);
DISPLAY 0.808511 (-2150 1325);
PAINT VIOLET (-2150 1325);
FORCEPROP 2 LAST CDS_LIB mstr_symbols
J 0
(-1950 1500);
PAINT ORANGE (-1950 1500);
DISPLAY INVISIBLE (-1950 1500);
FORCEPROP 2 LAST BOM_COST SM_CONTROLLER
J 0
(-2150 1450);
PAINT MONO (-2150 1450);
DISPLAY INVISIBLE (-2150 1450);
FORCEPROP 1 LAST COMMENT_BODY TRUE
J 0
(-1925 1600);
DISPLAY 1.319149 (-1925 1600);
PAINT GREEN (-1925 1600);
DISPLAY INVISIBLE (-1925 1600);
FORCEPROP 2 LAST ROOM PVCCIN_CPU1_DECAP_VR
J 0
(-2150 1450);
PAINT MONO (-2150 1450);
DISPLAY INVISIBLE (-2150 1450);
FORCEADD CAD_NOTE..1
(-2875 4975);
FORCEPROP 0 LAST L1 * PLACE PULL-UP RESISTORS CLOSE TO GTL2014
J 0
(-3025 4875);
DISPLAY 0.638298 (-3025 4875);
PAINT WHITE (-3025 4875);
FORCEPROP 2 LAST CDS_LIB mstr_symbols
J 0
(-2875 4975);
PAINT ORANGE (-2875 4975);
DISPLAY INVISIBLE (-2875 4975);
FORCEPROP 2 LAST BOM_COST SM_CONTROLLER
J 0
(-3025 4925);
PAINT WHITE (-3025 4925);
DISPLAY INVISIBLE (-3025 4925);
FORCEPROP 1 LAST COMMENT_BODY TRUE
J 0
(-2850 5075);
DISPLAY 1.319149 (-2850 5075);
PAINT WHITE (-2850 5075);
DISPLAY INVISIBLE (-2850 5075);
FORCEPROP 2 LAST ROOM BMC
J 0
(-3025 4925);
PAINT WHITE (-3025 4925);
DISPLAY INVISIBLE (-3025 4925);
FORCEADD CAD_NOTE..1
(-2875 2975);
FORCEPROP 0 LAST L1 * PLACE PULL-UP RESISTORS CLOSE TO GTL2014
J 0
(-3025 2850);
DISPLAY 0.638298 (-3025 2850);
PAINT WHITE (-3025 2850);
FORCEPROP 2 LAST BOM_COST SM_CONTROLLER
J 0
(-3025 2925);
PAINT WHITE (-3025 2925);
DISPLAY INVISIBLE (-3025 2925);
FORCEPROP 2 LAST CDS_LIB mstr_symbols
J 0
(-2875 2975);
PAINT ORANGE (-2875 2975);
DISPLAY INVISIBLE (-2875 2975);
FORCEPROP 1 LAST COMMENT_BODY TRUE
J 0
(-2850 3075);
DISPLAY 1.319149 (-2850 3075);
PAINT WHITE (-2850 3075);
DISPLAY INVISIBLE (-2850 3075);
FORCEPROP 2 LAST ROOM BMC
J 0
(-3025 2925);
PAINT WHITE (-3025 2925);
DISPLAY INVISIBLE (-3025 2925);
FORCEADD CAD_NOTE..1
(-4700 5125);
FORCEPROP 0 LAST L1 PLACE PULLUP RESISTOR WITHIN
J 0
(-4850 5025);
DISPLAY 0.638298 (-4850 5025);
PAINT ORANGE (-4850 5025);
FORCEPROP 0 LAST L2 2.5 INCH OF CPU0
J 0
(-4850 4975);
DISPLAY 0.638298 (-4850 4975);
PAINT ORANGE (-4850 4975);
FORCEPROP 2 LAST BOM_COST SM_CONTROLLER
J 0
(-4850 5075);
PAINT WHITE (-4850 5075);
DISPLAY INVISIBLE (-4850 5075);
FORCEPROP 2 LAST CDS_LIB mstr_symbols
J 0
(-4700 5125);
PAINT ORANGE (-4700 5125);
DISPLAY INVISIBLE (-4700 5125);
FORCEPROP 1 LAST COMMENT_BODY TRUE
J 0
(-4675 5225);
DISPLAY 1.319149 (-4675 5225);
PAINT WHITE (-4675 5225);
DISPLAY INVISIBLE (-4675 5225);
FORCEPROP 2 LAST ROOM PROC_SIDEBAND
J 0
(-4850 5075);
PAINT WHITE (-4850 5075);
DISPLAY INVISIBLE (-4850 5075);
FORCEADD CAD_NOTE..1
(-3775 1050);
FORCEPROP 0 LAST L1 * PLACE SERIES RESISTORS CLOSE TO  GTL2014
J 0
(-3925 950);
DISPLAY 0.808511 (-3925 950);
PAINT WHITE (-3925 950);
FORCEPROP 2 LAST CDS_LIB mstr_symbols
J 0
(-3775 1050);
PAINT MONO (-3775 1050);
DISPLAY INVISIBLE (-3775 1050);
FORCEPROP 2 LAST BOM_COST SM_CONTROLLER
J 0
(-3925 1000);
PAINT WHITE (-3925 1000);
DISPLAY INVISIBLE (-3925 1000);
FORCEPROP 1 LAST COMMENT_BODY TRUE
J 0
(-3750 1150);
DISPLAY 1.319149 (-3750 1150);
PAINT WHITE (-3750 1150);
DISPLAY INVISIBLE (-3750 1150);
FORCEPROP 2 LAST ROOM BMC
J 0
(-3925 1000);
PAINT WHITE (-3925 1000);
DISPLAY INVISIBLE (-3925 1000);
FORCEADD CAD_NOTE..1
(-4425 3425);
FORCEPROP 0 LAST L1 PLACE ALL COMPONENTS NEAR GTL CONVERTER
J 0
(-4575 3325);
DISPLAY 0.638298 (-4575 3325);
PAINT ORANGE (-4575 3325);
FORCEPROP 2 LAST CDS_LIB mstr_symbols
J 0
(-4425 3425);
PAINT ORANGE (-4425 3425);
DISPLAY INVISIBLE (-4425 3425);
FORCEPROP 2 LAST BOM_COST SM_CONTROLLER
J 0
(-4575 3375);
PAINT WHITE (-4575 3375);
DISPLAY INVISIBLE (-4575 3375);
FORCEPROP 1 LAST COMMENT_BODY TRUE
J 0
(-4400 3525);
DISPLAY 1.319149 (-4400 3525);
PAINT WHITE (-4400 3525);
DISPLAY INVISIBLE (-4400 3525);
FORCEPROP 2 LAST ROOM PROC_SIDEBAND
J 0
(-4575 3375);
PAINT WHITE (-4575 3375);
DISPLAY INVISIBLE (-4575 3375);
FORCEADD CAD_NOTE..1
(-2875 3525);
FORCEPROP 0 LAST L1 * PLACE  RESISTORS CLOSE TO  GTL2014
J 0
(-3350 3425);
DISPLAY 0.638298 (-3350 3425);
PAINT WHITE (-3350 3425);
FORCEPROP 2 LAST CDS_LIB mstr_symbols
J 0
(-2875 3525);
PAINT MONO (-2875 3525);
DISPLAY INVISIBLE (-2875 3525);
FORCEPROP 2 LAST BOM_COST SM_CONTROLLER
J 0
(-3025 3475);
PAINT WHITE (-3025 3475);
DISPLAY INVISIBLE (-3025 3475);
FORCEPROP 1 LAST COMMENT_BODY TRUE
J 0
(-2850 3625);
DISPLAY 1.319149 (-2850 3625);
PAINT WHITE (-2850 3625);
DISPLAY INVISIBLE (-2850 3625);
FORCEPROP 2 LAST ROOM BMC
J 0
(-3025 3475);
PAINT WHITE (-3025 3475);
DISPLAY INVISIBLE (-3025 3475);
FORCEADD CAD_NOTE..1
(-3950 3875);
FORCEPROP 0 LAST L1 PLACE SERIES RESISTORS NEAR GTL CONVERTER
J 0
(-4100 3775);
DISPLAY 0.638298 (-4100 3775);
PAINT ORANGE (-4100 3775);
FORCEPROP 2 LAST CDS_LIB mstr_symbols
J 0
(-3950 3875);
PAINT WHITE (-3950 3875);
DISPLAY INVISIBLE (-3950 3875);
FORCEPROP 1 LAST COMMENT_BODY TRUE
J 0
(-3925 3975);
DISPLAY 1.319149 (-3925 3975);
PAINT WHITE (-3925 3975);
DISPLAY INVISIBLE (-3925 3975);
FORCEADD DESIGN_NOTE..1
(-2150 3675);
PAINT PURPLE (-2150 3675);
FORCEPROP 0 LAST L1 THE GTL2014 IS BEING USED AS GTL TO LVTTL CONVERTER, SO
J 0
(-2350 3550);
DISPLAY 0.808511 (-2350 3550);
PAINT VIOLET (-2350 3550);
FORCEPROP 0 LAST L2 THE PINS 'BX' ARE INPUTS & 'AX' OUTPUTS ARE PUSH-PULL.
J 0
(-2350 3500);
DISPLAY 0.808511 (-2350 3500);
PAINT VIOLET (-2350 3500);
FORCEPROP 0 LAST L3 VREF IS SET AT 2/3 OF VCCIO
J 0
(-2350 3450);
DISPLAY 0.808511 (-2350 3450);
PAINT VIOLET (-2350 3450);
FORCEPROP 2 LAST BOM_COST SM_CONTROLLER
J 0
(-2350 3625);
PAINT MONO (-2350 3625);
DISPLAY INVISIBLE (-2350 3625);
FORCEPROP 2 LAST CDS_LIB mstr_symbols
J 0
(-2150 3675);
PAINT ORANGE (-2150 3675);
DISPLAY INVISIBLE (-2150 3675);
FORCEPROP 1 LAST COMMENT_BODY TRUE
J 0
(-2125 3775);
DISPLAY 1.319149 (-2125 3775);
PAINT GREEN (-2125 3775);
DISPLAY INVISIBLE (-2125 3775);
FORCEPROP 2 LAST ROOM PVCCIN_CPU1_DECAP_VR
J 0
(-2350 3625);
PAINT MONO (-2350 3625);
DISPLAY INVISIBLE (-2350 3625);
FORCEADD INTEL_CORP_BPAGE..1
(2225 675);
FORCEPROP 1 LAST CDS_CON_LAST_MODIFIED Tue Dec 01 11:51:48 2015
J 0
(800 1000);
PAINT ORANGE (800 1000);
DISPLAY INVISIBLE (800 1000);
FORCEPROP 1 LAST CUSTOM_TXT_CDS <CURRENT_DESIGN_SHEET> OF <TOTAL_DESIGN_SHEETS>
J 0
(1725 700);
PAINT GREEN (1725 700);
FORCEPROP 1 LAST CUSTOM_TXT_CDS <CON_LAST_MODIFIED>
J 0
(300 1025);
PAINT GREEN (300 1025);
FORCEPROP 2 LAST CUSTOM_TXT_CDS <XR_PAGE_TITLE>
J 0
(-5665 5925);
DISPLAY 0.638298 (-5665 5925);
PAINT PINK (-5665 5925);
DISPLAY INVISIBLE (-5665 5925);
FORCEPROP 1 LAST SCH_ADDRESS3 Santa Clara, CA 95052-8119
J 0
(-1750 700);
DISPLAY 0.617021 (-1750 700);
PAINT GREEN (-1750 700);
FORCEPROP 1 LAST SCH_ADDRESS2 P.O. BOX 58119
J 0
(-1750 750);
DISPLAY 0.617021 (-1750 750);
PAINT GREEN (-1750 750);
FORCEPROP 1 LAST SCH_ADDRESS1 2200 Mission College Blvd.
J 0
(-1750 800);
DISPLAY 0.617021 (-1750 800);
PAINT GREEN (-1750 800);
FORCEPROP 1 LAST SCH_TITLE CPU SIDE BAND: MISC
J 0
(-5725 725);
DISPLAY 1.212766 (-5725 725);
PAINT ORANGE (-5725 725);
FORCEPROP 1 LAST SCH_REV 2.420
J 0
(1975 825);
DISPLAY 0.978723 (1975 825);
PAINT YELLOW (1975 825);
FORCEPROP 1 LAST SCH_DEPT BESD
J 1
(-2225 775);
DISPLAY 1.212766 (-2225 775);
PAINT YELLOW (-2225 775);
FORCEPROP 1 LAST SCH_NUMBER H4694802
J 0
(925 825);
DISPLAY 1.212766 (925 825);
PAINT YELLOW (925 825);
FORCEPROP 2 LAST CDS_LIB mstr_symbols
J 0
(2225 675);
PAINT MONO (2225 675);
DISPLAY INVISIBLE (2225 675);
FORCEPROP 2 LAST PAGE_BORDER TRUE
J 0
(-5665 5925);
DISPLAY 0.638298 (-5665 5925);
PAINT PINK (-5665 5925);
DISPLAY INVISIBLE (-5665 5925);
FORCEPROP 1 LAST COMMENT_BODY TRUE
J 0
(2237 687);
DISPLAY 0.468085 (2237 687);
PAINT GREEN (2237 687);
DISPLAY INVISIBLE (2237 687);
FORCEPROP 2 LAST CDS_XR_PAGE_TITLE CR-92 : @BASEBOARD_FAB2_LIB.BASEBOARD_FAB2(SCH_1):PAGE92
J 0
(-5665 5925);
DISPLAY 0.638298 (-5665 5925);
PAINT PINK (-5665 5925);
DISPLAY INVISIBLE (-5665 5925);
WIRE 16 -1 (-2900 4700)(-2900 4625);
WIRE 16 -1 (125 5300)(125 5375);
WIRE 16 -1 (-2275 3950)(-2550 3950);
WIRE 16 -1 (-2550 3950)(-2550 3900);
WIRE 16 -1 (-2275 3900)(-2550 3900);
WIRE 16 -1 (-2550 3900)(-2550 3850);
WIRE 16 -1 (-2550 3850)(-2275 3850);
WIRE 16 -1 (-2550 3850)(-2550 3775);
WIRE 16 -1 (-2200 1750)(-2475 1750);
WIRE 16 -1 (-2475 1750)(-2475 1700);
WIRE 16 -1 (-2200 1700)(-2475 1700);
WIRE 16 -1 (-2475 1700)(-2475 1650);
WIRE 16 -1 (-2475 1650)(-2200 1650);
WIRE 16 -1 (-2475 1650)(-2475 1575);
WIRE 16 -1 (-300 4725)(-300 4550);
WIRE 16 -1 (-300 4550)(125 4550);
WIRE 16 -1 (125 4700)(125 4550);
WIRE 16 -1 (125 4550)(125 4500);
WIRE 16 -1 (-1025 4825)(-1025 4875);
WIRE 16 -1 (-1025 4875)(-1175 4875);
WIRE 16 -1 (-1175 4875)(-1175 4550);
WIRE 16 -1 (-1175 4900)(-1175 4875);
WIRE 16 -1 (-1175 4550)(-1375 4550);
WIRE 16 -1 (-575 4400)(-300 4400);
WIRE 16 -1 (-300 4375)(-300 4400);
WIRE 16 -1 (-75 2450)(-75 2275);
WIRE 16 -1 (-75 2275)(350 2275);
WIRE 16 -1 (350 2425)(350 2275);
WIRE 16 -1 (350 2275)(350 2225);
WIRE 16 -1 (350 3150)(350 3225);
WIRE 16 -1 (-500 2200)(-225 2200);
WIRE 16 -1 (-225 2175)(-225 2200);
WIRE 16 -1 (-900 2625)(-900 2675);
WIRE 16 -1 (-900 2675)(-1050 2675);
WIRE 16 -1 (-1050 2675)(-1050 2350);
WIRE 16 -1 (-1050 2700)(-1050 2675);
WIRE 16 -1 (-1050 2350)(-1300 2350);
WIRE 16 -1 (-4275 1900)(-4275 1950);
WIRE 16 -1 (-4600 1950)(-4275 1950);
WIRE 16 -1 (-4600 1925)(-4600 1950);
WIRE 16 -1 (-4600 1950)(-4600 2000);
WIRE 16 -1 (-2925 3800)(-2925 3700);
WIRE 16 -1 (-900 2400)(-900 2425);
WIRE 16 -1 (-2850 2425)(-2850 2650);
WIRE 16 -1 (-1025 4600)(-1025 4625);
WIRE 16 -1 (-4000 3050)(-4000 3125);
WIRE 16 -1 (-4350 4700)(-4350 4750);
WIRE 16 -1 (-4350 4750)(-4450 4750);
WIRE 16 -1 (-4450 4800)(-4450 4750);
WIRE 16 -1 (-4450 4750)(-4450 4700);
WIRE 16 -1 (-1375 4200)(-525 4200);
FORCEPROP 2 LAST SIG_NAME FM_CPU_CATERR_LVT3_R2_N
J 0
(-1250 4210);
DISPLAY 0.617021 (-1250 4210);
PAINT ORANGE (-1250 4210);
FORCEPROP 2 LASTPROP $XRERR UNIQUE?
J 0
(-1490 4210);
DISPLAY 0.638298 (-1490 4210);
PAINT MONO (-1490 4210);
DISPLAY INVISIBLE (-1490 4210);
WIRE 16 -1 (-525 4200)(-525 4000);
WIRE 16 -1 (-525 4000)(-225 4000);
WIRE 16 -1 (-1375 4150)(-575 4150);
FORCEPROP 2 LAST SIG_NAME FM_CPU1_FIVR_FAULT_R_LVT3
J 0
(-1250 4160);
DISPLAY 0.617021 (-1250 4160);
PAINT ORANGE (-1250 4160);
FORCEPROP 2 LASTPROP $XRERR UNIQUE?
J 0
(-1490 4160);
DISPLAY 0.638298 (-1490 4160);
PAINT MONO (-1490 4160);
DISPLAY INVISIBLE (-1490 4160);
WIRE 16 -1 (-575 4150)(-575 3750);
WIRE 16 -1 (-575 3750)(-225 3750);
WIRE 16 -1 (-25 4000)(1000 4000);
FORCEPROP 2 LAST SIG_NAME FM_CPU_CATERR_LVT3_N
J 0
(150 4010);
DISPLAY 0.617021 (150 4010);
PAINT ORANGE (150 4010);
WIRE 16 -1 (-5150 2800)(-4700 2800);
FORCEPROP 2 LAST SIG_NAME H_CPU0_ERR2_G_N
J 0
(-5150 2810);
DISPLAY 0.617021 (-5150 2810);
PAINT ORANGE (-5150 2810);
WIRE 16 -1 (-4675 2550)(-5150 2550);
FORCEPROP 2 LAST SIG_NAME H_CPU1_ERR2_G_N
J 0
(-5150 2560);
DISPLAY 0.617021 (-5150 2560);
PAINT ORANGE (-5150 2560);
WIRE 16 -1 (-4500 2800)(-4425 2800);
FORCEPROP 2 LAST SIG_NAME H_CPU_ERR2_G_R_N
J 0
(-4375 2685);
DISPLAY 0.617021 (-4375 2685);
PAINT ORANGE (-4375 2685);
FORCEPROP 2 LASTPROP $XRERR UNIQUE?
J 0
(-4615 2685);
DISPLAY 0.638298 (-4615 2685);
PAINT MONO (-4615 2685);
DISPLAY INVISIBLE (-4615 2685);
WIRE 16 -1 (-4425 2675)(-4425 2800);
WIRE 16 -1 (-4425 2675)(-4000 2675);
WIRE 16 -1 (-4425 2550)(-4425 2675);
WIRE 16 -1 (-4425 2550)(-4475 2550);
WIRE 16 -1 (-3775 2675)(-4000 2675);
WIRE 16 -1 (-4000 2850)(-4000 2675);
WIRE 16 2175 (-4700 4950)(-4100 4950);
WIRE 16 2175 (-4700 4050)(-4700 4950);
WIRE 16 2175 (-4100 4950)(-4100 4050);
WIRE 16 2175 (-4100 4050)(-4700 4050);
WIRE 16 -1 (-3875 4350)(-4450 4350);
WIRE 16 -1 (-4450 4500)(-4450 4350);
WIRE 16 -1 (-4450 4350)(-5100 4350);
FORCEPROP 2 LAST SIG_NAME H_CPU0_CATERR_G_N
J 0
(-5100 4360);
DISPLAY 0.617021 (-5100 4360);
PAINT ORANGE (-5100 4360);
WIRE 16 -1 (-4600 1725)(-4600 1550);
WIRE 16 -1 (-3875 1550)(-4600 1550);
WIRE 16 -1 (-5075 1550)(-4600 1550);
FORCEPROP 2 LAST SIG_NAME H_CPU0_MSMI_G_N
J 0
(-4900 1560);
DISPLAY 0.617021 (-4900 1560);
PAINT ORANGE (-4900 1560);
WIRE 16 -1 (-3825 1275)(-4275 1275);
WIRE 16 -1 (-4275 1700)(-4275 1275);
WIRE 16 -1 (-4275 1275)(-5075 1275);
FORCEPROP 2 LAST SIG_NAME H_CPU1_MSMI_G_N
J 0
(-4900 1285);
DISPLAY 0.617021 (-4900 1285);
PAINT ORANGE (-4900 1285);
WIRE 16 2175 (-4075 2150)(-4075 1175);
WIRE 16 2175 (-4925 2150)(-4075 2150);
WIRE 16 2175 (-4075 1175)(-4925 1175);
WIRE 16 2175 (-4925 1175)(-4925 2150);
WIRE 16 2175 (-3400 3300)(-3400 2375);
WIRE 16 2175 (-4800 3300)(-3400 3300);
WIRE 16 2175 (-3400 2375)(-4800 2375);
WIRE 16 2175 (-4800 2375)(-4800 3300);
WIRE 16 -1 (-4350 4500)(-4350 4100);
WIRE 16 -1 (-3850 4100)(-4350 4100);
WIRE 16 -1 (-5100 4100)(-4350 4100);
FORCEPROP 2 LAST SIG_NAME H_CPU1_CATERR_G_N
J 0
(-5100 4110);
DISPLAY 0.617021 (-5100 4110);
PAINT ORANGE (-5100 4110);
WIRE 16 2175 (-3475 1150)(-3475 1800);
WIRE 16 2175 (-3950 1150)(-3475 1150);
WIRE 16 2175 (-3475 1800)(-3950 1800);
WIRE 16 2175 (-3950 1800)(-3950 1150);
WIRE 16 -1 (-2950 1900)(-2200 1900);
WIRE 16 -1 (-2950 1425)(-2950 1900);
FORCEPROP 2 LAST SIG_NAME H_CPU_MSMI_G_N
J 0
(-2810 1910);
DISPLAY 0.617021 (-2810 1910);
PAINT ORANGE (-2810 1910);
FORCEPROP 2 LASTPROP $XRERR UNIQUE?
J 0
(-3050 1910);
DISPLAY 0.638298 (-3050 1910);
PAINT MONO (-3050 1910);
DISPLAY INVISIBLE (-3050 1910);
WIRE 16 -1 (-2950 1425)(-3550 1425);
WIRE 16 -1 (-3550 1425)(-3550 1550);
WIRE 16 -1 (-3550 1425)(-3550 1275);
WIRE 16 -1 (-3550 1275)(-3625 1275);
WIRE 16 -1 (-3550 1550)(-3675 1550);
WIRE 16 -1 (-3175 1950)(-2200 1950);
FORCEPROP 2 LAST SIG_NAME H_CPU0_FIVR_FAULT_G
J 0
(-2808 1957);
DISPLAY 0.617021 (-2808 1957);
PAINT ORANGE (-2808 1957);
WIRE 16 -1 (-3500 2675)(-3575 2675);
WIRE 16 -1 (-3500 2000)(-3500 2675);
WIRE 16 -1 (-3500 2000)(-2200 2000);
FORCEPROP 2 LAST SIG_NAME H_CPU_ERR2_GTL_N
J 0
(-2810 2010);
DISPLAY 0.617021 (-2810 2010);
PAINT ORANGE (-2810 2010);
FORCEPROP 2 LASTPROP $XRERR UNIQUE?
J 0
(-3050 2010);
DISPLAY 0.638298 (-3050 2010);
PAINT MONO (-3050 2010);
DISPLAY INVISIBLE (-3050 2010);
WIRE 16 2175 (-2600 2125)(-2600 2800);
WIRE 16 2175 (-3025 2125)(-2600 2125);
WIRE 16 2175 (-2600 2800)(-3025 2800);
WIRE 16 2175 (-3025 2125)(-3025 2800);
WIRE 16 -1 (-2850 2225)(-2850 2050);
WIRE 16 -1 (-2200 2050)(-2850 2050);
FORCEPROP 2 LAST SIG_NAME H_CPU0_THERMTRIP_G_N
J 0
(-2812 2065);
DISPLAY 0.617021 (-2812 2065);
PAINT ORANGE (-2812 2065);
WIRE 16 -1 (-3175 2050)(-2850 2050);
WIRE 16 2175 (-2700 4075)(-2700 3600);
WIRE 16 2175 (-2975 4075)(-2700 4075);
WIRE 16 2175 (-2700 3600)(-2975 3600);
WIRE 16 2175 (-2975 3600)(-2975 4075);
WIRE 16 -1 (-550 1250)(-200 1250);
WIRE 16 -1 (-550 1900)(-550 1250);
WIRE 16 -1 (-1300 1900)(-550 1900);
FORCEPROP 2 LAST SIG_NAME FM_CPU_MSMI_LVT3_R_N
J 0
(-1175 1910);
DISPLAY 0.617021 (-1175 1910);
PAINT ORANGE (-1175 1910);
FORCEPROP 2 LASTPROP $XRERR UNIQUE?
J 0
(-1415 1910);
DISPLAY 0.638298 (-1415 1910);
PAINT MONO (-1415 1910);
DISPLAY INVISIBLE (-1415 1910);
WIRE 16 -1 (-450 1800)(-200 1800);
WIRE 16 -1 (-450 2000)(-450 1800);
WIRE 16 -1 (-1300 2000)(-450 2000);
FORCEPROP 2 LAST SIG_NAME FM_CPU_ERR2_LVT3_R_N
J 0
(-1175 2010);
DISPLAY 0.617021 (-1175 2010);
PAINT ORANGE (-1175 2010);
FORCEPROP 2 LASTPROP $XRERR UNIQUE?
J 0
(-1415 2010);
DISPLAY 0.638298 (-1415 2010);
PAINT MONO (-1415 2010);
DISPLAY INVISIBLE (-1415 2010);
WIRE 16 -1 (-500 1550)(-200 1550);
WIRE 16 -1 (-500 1950)(-500 1550);
WIRE 16 -1 (-1300 1950)(-500 1950);
FORCEPROP 2 LAST SIG_NAME FM_CPU0_FIVR_FAULT_R_LVT3
J 0
(-1175 1960);
DISPLAY 0.617021 (-1175 1960);
PAINT ORANGE (-1175 1960);
FORCEPROP 2 LASTPROP $XRERR UNIQUE?
J 0
(-1415 1960);
DISPLAY 0.638298 (-1415 1960);
PAINT MONO (-1415 1960);
DISPLAY INVISIBLE (-1415 1960);
WIRE 16 -1 (-1300 2200)(-700 2200);
FORCEPROP 2 LAST SIG_NAME PD_GTL2104_DIR_0
J 0
(-1187 2223);
DISPLAY 0.617021 (-1187 2223);
PAINT ORANGE (-1187 2223);
FORCEPROP 2 LASTPROP $XRERR UNIQUE?
J 0
(-1427 2223);
DISPLAY 0.638298 (-1427 2223);
PAINT MONO (-1427 2223);
DISPLAY INVISIBLE (-1427 2223);
WIRE 16 -1 (-1300 2050)(-225 2050);
FORCEPROP 2 LAST SIG_NAME FM_CPU0_THERMTRIP_LVT3_R_N
J 0
(-1175 2060);
DISPLAY 0.617021 (-1175 2060);
PAINT ORANGE (-1175 2060);
FORCEPROP 2 LASTPROP $XRERR UNIQUE?
J 0
(-1415 2060);
DISPLAY 0.638298 (-1415 2060);
PAINT MONO (-1415 2060);
DISPLAY INVISIBLE (-1415 2060);
WIRE 16 -1 (350 2950)(350 2725);
WIRE 16 -1 (350 2725)(350 2625);
WIRE 16 -1 (-75 2725)(350 2725);
WIRE 16 -1 (-75 2650)(-75 2725);
WIRE 16 -1 (-75 2725)(-525 2725);
FORCEPROP 0 LAST VOLTAGE +0.7 V
J 0
(-325 2800);
DISPLAY 1.404255 (-325 2800);
PAINT SKYBLUE (-325 2800);
DISPLAY INVISIBLE (-325 2800);
FORCEPROP 2 LAST SIG_NAME P0V7_GTL2104_VREF_0
J 0
(-335 2735);
DISPLAY 0.617021 (-335 2735);
PAINT ORANGE (-335 2735);
FORCEPROP 2 LASTPROP $XRERR UNIQUE?
J 0
(-575 2735);
DISPLAY 0.638298 (-575 2735);
PAINT MONO (-575 2735);
DISPLAY INVISIBLE (-575 2735);
WIRE 16 -1 (-525 2725)(-525 2300);
WIRE 16 -1 (-525 2300)(-1300 2300);
WIRE 16 -1 (-1375 4100)(-675 4100);
FORCEPROP 2 LAST SIG_NAME PWRGD_CPUPWRGD_R1
J 0
(-1250 4110);
DISPLAY 0.617021 (-1250 4110);
PAINT ORANGE (-1250 4110);
FORCEPROP 2 LASTPROP $XRERR UNIQUE?
J 0
(-1490 4110);
DISPLAY 0.638298 (-1490 4110);
PAINT MONO (-1490 4110);
DISPLAY INVISIBLE (-1490 4110);
WIRE 16 -1 (-675 4100)(-675 3550);
WIRE 16 -1 (-675 3550)(-225 3550);
WIRE 16 2175 (-3525 4525)(-4025 4525);
WIRE 16 2175 (-3525 3950)(-3525 4525);
WIRE 16 2175 (-4025 4525)(-4025 3950);
WIRE 16 2175 (-4025 3950)(-3525 3950);
WIRE 16 -1 (-3675 4350)(-3450 4350);
WIRE 16 -1 (-3450 4350)(-3450 4200);
WIRE 16 -1 (-3450 4200)(-2275 4200);
FORCEPROP 2 LAST SIG_NAME H_CPU_CATERR_G_N
J 0
(-2800 4210);
DISPLAY 0.617021 (-2800 4210);
PAINT ORANGE (-2800 4210);
FORCEPROP 2 LASTPROP $XRERR UNIQUE?
J 0
(-3040 4210);
DISPLAY 0.638298 (-3040 4210);
PAINT MONO (-3040 4210);
DISPLAY INVISIBLE (-3040 4210);
WIRE 16 -1 (-3450 4100)(-3450 4200);
WIRE 16 -1 (-3450 4100)(-3650 4100);
WIRE 16 2175 (-2625 4325)(-2625 4850);
WIRE 16 2175 (-2625 4325)(-3075 4325);
WIRE 16 2175 (-3075 4850)(-2625 4850);
WIRE 16 2175 (-3075 4325)(-3075 4850);
WIRE 16 -1 (-2900 4425)(-2900 4250);
WIRE 16 -1 (-2275 4250)(-2900 4250);
FORCEPROP 2 LAST SIG_NAME H_CPU1_THERMTRIP_G_N
J 0
(-2800 4265);
DISPLAY 0.617021 (-2800 4265);
PAINT ORANGE (-2800 4265);
WIRE 16 -1 (-3000 4250)(-2900 4250);
WIRE 16 -1 (-3000 4150)(-2925 4150);
WIRE 16 -1 (-2925 4150)(-2275 4150);
FORCEPROP 2 LAST SIG_NAME H_CPU1_FIVR_FAULT_G
J 0
(-2800 4157);
DISPLAY 0.617021 (-2800 4157);
PAINT ORANGE (-2800 4157);
WIRE 16 -1 (-2925 4000)(-2925 4150);
WIRE 16 -1 (-3000 4100)(-2275 4100);
FORCEPROP 2 LAST SIG_NAME PWRGD_CPUPWRGD_GTL
J 0
(-2800 4110);
DISPLAY 0.617021 (-2800 4110);
PAINT ORANGE (-2800 4110);
WIRE 16 -1 (-1375 4250)(-225 4250);
FORCEPROP 2 LAST SIG_NAME FM_CPU1_THERMTRIP_LVT3_R_N
J 0
(-1250 4260);
DISPLAY 0.617021 (-1250 4260);
PAINT ORANGE (-1250 4260);
FORCEPROP 2 LASTPROP $XRERR UNIQUE?
J 0
(-1490 4260);
DISPLAY 0.638298 (-1490 4260);
PAINT MONO (-1490 4260);
DISPLAY INVISIBLE (-1490 4260);
WIRE 16 -1 (-1375 4400)(-775 4400);
FORCEPROP 2 LAST SIG_NAME PD_GTL2104_DIR_1
J 0
(-1237 4423);
DISPLAY 0.617021 (-1237 4423);
PAINT ORANGE (-1237 4423);
FORCEPROP 2 LASTPROP $XRERR UNIQUE?
J 0
(-1477 4423);
DISPLAY 0.638298 (-1477 4423);
PAINT MONO (-1477 4423);
DISPLAY INVISIBLE (-1477 4423);
WIRE 16 -1 (125 5000)(125 4900);
WIRE 16 -1 (125 5100)(125 5000);
WIRE 16 -1 (-300 5000)(125 5000);
WIRE 16 -1 (-300 4925)(-300 5000);
WIRE 16 -1 (-300 5000)(-750 5000);
FORCEPROP 0 LAST VOLTAGE +0.7 V
J 0
(-550 5075);
DISPLAY 1.404255 (-550 5075);
PAINT SKYBLUE (-550 5075);
DISPLAY INVISIBLE (-550 5075);
FORCEPROP 2 LAST SIG_NAME P0V7_GTL2104_VREF_1
J 0
(-560 5010);
DISPLAY 0.617021 (-560 5010);
PAINT ORANGE (-560 5010);
FORCEPROP 2 LASTPROP $XRERR UNIQUE?
J 0
(-800 5010);
DISPLAY 0.638298 (-800 5010);
PAINT MONO (-800 5010);
DISPLAY INVISIBLE (-800 5010);
WIRE 16 -1 (-750 5000)(-750 4500);
WIRE 16 -1 (-750 4500)(-1375 4500);
WIRE 16 -1 (-25 3750)(1000 3750);
FORCEPROP 2 LAST SIG_NAME FM_CPU1_FIVR_FAULT_LVT3
J 0
(150 3760);
DISPLAY 0.617021 (150 3760);
PAINT ORANGE (150 3760);
WIRE 16 -1 (-25 4250)(1000 4250);
FORCEPROP 2 LAST SIG_NAME FM_CPU1_THERMTRIP_LVT3_N
J 0
(150 4260);
DISPLAY 0.617021 (150 4260);
PAINT ORANGE (150 4260);
WIRE 16 -1 (-25 2050)(1025 2050);
FORCEPROP 2 LAST SIG_NAME FM_CPU0_THERMTRIP_LVT3_N
J 0
(200 2060);
DISPLAY 0.617021 (200 2060);
PAINT ORANGE (200 2060);
WIRE 16 -1 (0 1550)(1025 1550);
FORCEPROP 2 LAST SIG_NAME FM_CPU0_FIVR_FAULT_LVT3
J 0
(200 1560);
DISPLAY 0.617021 (200 1560);
PAINT ORANGE (200 1560);
WIRE 16 -1 (-25 3550)(1000 3550);
FORCEPROP 2 LAST SIG_NAME PWRGD_CPUPWRGD
J 0
(150 3560);
DISPLAY 0.617021 (150 3560);
PAINT ORANGE (150 3560);
WIRE 16 -1 (0 1250)(1025 1250);
FORCEPROP 2 LAST SIG_NAME FM_CPU_MSMI_LVT3_N
J 0
(200 1260);
DISPLAY 0.617021 (200 1260);
PAINT ORANGE (200 1260);
WIRE 16 -1 (0 1800)(1025 1800);
FORCEPROP 2 LAST SIG_NAME FM_CPU_ERR2_LVT3_N
J 0
(200 1810);
DISPLAY 0.617021 (200 1810);
PAINT ORANGE (200 1810);
DOT 1 (-3550 1425);
DOT 1 (350 2725);
DOT 1 (350 2275);
DOT 1 (-75 2725);
DOT 1 (-1050 2675);
DOT 1 (-2475 1700);
DOT 1 (-4600 1550);
DOT 1 (-4275 1275);
DOT 1 (-4600 1950);
DOT 1 (-4425 2675);
DOT 1 (-2550 3900);
DOT 1 (125 5000);
DOT 1 (125 4550);
DOT 1 (-300 5000);
DOT 1 (-1175 4875);
DOT 1 (-2900 4250);
DOT 1 (-3450 4200);
DOT 1 (-2550 3850);
DOT 1 (-4450 4750);
DOT 1 (-4450 4350);
DOT 1 (-4350 4100);
DOT 1 (-2850 2050);
DOT 1 (-4000 2675);
DOT 1 (-2925 4150);
DOT 1 (-2475 1650);
FORCENOTE
ROOM=PROC_SIDEBAND
(-5658 922) 0;
DISPLAY LEFT (-5658 922);
DISPLAY 1.276596 (-5658 922);
PAINT PURPLE (-5658 922);
FORCENOTE
BOM_COST=PROC_SIDEBAND
(-5683 822) 0;
DISPLAY LEFT (-5683 822);
DISPLAY 1.276596 (-5683 822);
PAINT PURPLE (-5683 822);
QUIT
